FILE_TYPE = MACRO_DRAWING;
SET COLOR_WIRE YELLOW;
SET COLOR_PROP ORANGE;
SET COLOR_DOT WHITE;
SET COLOR_ARC YELLOW;
SET COLOR_BODY GREEN;
SET COLOR_NOTE PURPLE;
SET PROP_DISPLAY VALUE;
SET PAGE_NUMBER P175;
FORCEADD OFFPAGE..5
(-9125 1175);
FORCEPROP 2 LAST $XR0 80 
J 0
(-9349 1175);
DISPLAY 0.638298 (-9349 1175);
PAINT MONO (-9349 1175);
FORCEPROP 2 LAST PATH I211
J 0
(-9375 1225);
DISPLAY 1.021277 (-9375 1225);
DISPLAY INVISIBLE (-9375 1225);
FORCEPROP 1 LAST COMMENT_BODY TRUE
J 0
(-9025 1100);
DISPLAY 0.872340 (-9025 1100);
PAINT GREEN (-9025 1100);
DISPLAY INVISIBLE (-9025 1100);
FORCEPROP 1 LAST OFFPAGE TRUE
J 0
(-8800 1050);
DISPLAY 0.872340 (-8800 1050);
PAINT GREEN (-8800 1050);
DISPLAY INVISIBLE (-8800 1050);
FORCEPROP 2 LAST CDS_LIB standard
J 0
(-9125 1175);
DISPLAY INVISIBLE (-9125 1175);
FORCEADD OFFPAGE..1
(-9950 2900);
FORCEPROP 2 LAST $XR0 27 
J 0
(-10261 2900);
DISPLAY 0.638298 (-10261 2900);
PAINT MONO (-10261 2900);
FORCEPROP 2 LAST PATH I214
J 0
(-10150 2950);
DISPLAY 1.021277 (-10150 2950);
DISPLAY INVISIBLE (-10150 2950);
FORCEPROP 1 LAST COMMENT_BODY TRUE
J 0
(-9825 2800);
DISPLAY 0.872340 (-9825 2800);
PAINT GREEN (-9825 2800);
DISPLAY INVISIBLE (-9825 2800);
FORCEPROP 1 LAST OFFPAGE TRUE
J 0
(-9625 2775);
DISPLAY 0.872340 (-9625 2775);
PAINT GREEN (-9625 2775);
DISPLAY INVISIBLE (-9625 2775);
FORCEPROP 2 LAST CDS_LIB standard
J 0
(-9950 2900);
DISPLAY INVISIBLE (-9950 2900);
FORCEADD OFFPAGE..1
(-9950 3275);
FORCEPROP 2 LAST $XR0 27 
J 0
(-10261 3275);
DISPLAY 0.638298 (-10261 3275);
PAINT MONO (-10261 3275);
FORCEPROP 2 LAST PATH I215
J 0
(-10150 3325);
DISPLAY 1.021277 (-10150 3325);
DISPLAY INVISIBLE (-10150 3325);
FORCEPROP 1 LAST COMMENT_BODY TRUE
J 0
(-9825 3175);
DISPLAY 0.872340 (-9825 3175);
PAINT GREEN (-9825 3175);
DISPLAY INVISIBLE (-9825 3175);
FORCEPROP 1 LAST OFFPAGE TRUE
J 0
(-9625 3150);
DISPLAY 0.872340 (-9625 3150);
PAINT GREEN (-9625 3150);
DISPLAY INVISIBLE (-9625 3150);
FORCEPROP 2 LAST CDS_LIB standard
J 0
(-9950 3275);
DISPLAY INVISIBLE (-9950 3275);
FORCEADD Q_RES..1
(-8575 1025);
FORCEPROP 1 LAST LOCATION PR53
J 0
(-8700 1075);
DISPLAY 0.489362 (-8700 1075);
PAINT SKYBLUE (-8700 1075);
FORCEPROP 0 LAST $SEC 1
J 0
(-8625 1125);
DISPLAY 0.680851 (-8625 1125);
PAINT MONO (-8625 1125);
DISPLAY INVISIBLE (-8625 1125);
FORCEPROP 0 LAST CDS_SEC 1
J 0
(-8625 1125);
DISPLAY 1.021277 (-8625 1125);
DISPLAY INVISIBLE (-8625 1125);
FORCEPROP 1 LASTPIN (-8675 1025) $PN 1
J 0
(-8663 1037);
DISPLAY 0.489362 (-8663 1037);
PAINT MONO (-8663 1037);
FORCEPROP 1 LASTPIN (-8475 1025) $PN 2
J 0
(-8513 1037);
DISPLAY 0.489362 (-8513 1037);
PAINT MONO (-8513 1037);
FORCEPROP 1 LAST MATERIAL CHIP
J 0
(-8575 975);
DISPLAY 0.489362 (-8575 975);
PAINT SKYBLUE (-8575 975);
FORCEPROP 1 LAST VALUE 40.2K
J 2
(-8425 1075);
DISPLAY 0.489362 (-8425 1075);
PAINT SKYBLUE (-8425 1075);
FORCEPROP 1 LAST TOLERANCE 1%
J 0
(-8475 975);
DISPLAY 0.489362 (-8475 975);
PAINT SKYBLUE (-8475 975);
FORCEPROP 1 LAST PACK_TYPE 0402LF
J 0
(-8725 975);
DISPLAY 0.489362 (-8725 975);
PAINT SKYBLUE (-8725 975);
FORCEPROP 1 LAST PART_NUMBER TMP_QCS34022FB15
J 0
(-8450 975);
DISPLAY 0.510638 (-8450 975);
PAINT SKYBLUE (-8450 975);
DISPLAY INVISIBLE (-8450 975);
FORCEPROP 1 LAST WATTAGE 1/16W
J 2
(-8200 925);
DISPLAY 0.510638 (-8200 925);
PAINT SKYBLUE (-8200 925);
DISPLAY INVISIBLE (-8200 925);
FORCEPROP 1 LAST PATH I219
J 0
(-8625 1175);
DISPLAY 0.978723 (-8625 1175);
PAINT WHITE (-8625 1175);
DISPLAY INVISIBLE (-8625 1175);
FORCEPROP 2 LAST CDS_LIB pure_quanta
J 0
(-8575 1025);
DISPLAY INVISIBLE (-8575 1025);
FORCEADD Q_RES..1
(-7350 850);
FORCEPROP 1 LAST LOCATION PR74
J 0
(-7375 900);
DISPLAY 0.489362 (-7375 900);
PAINT SKYBLUE (-7375 900);
FORCEPROP 0 LAST $SEC 1
J 0
(-7400 950);
DISPLAY 0.680851 (-7400 950);
PAINT MONO (-7400 950);
DISPLAY INVISIBLE (-7400 950);
FORCEPROP 0 LAST CDS_SEC 1
J 0
(-7400 950);
DISPLAY 1.021277 (-7400 950);
DISPLAY INVISIBLE (-7400 950);
FORCEPROP 1 LASTPIN (-7450 850) $PN 1
J 0
(-7438 862);
DISPLAY 0.489362 (-7438 862);
PAINT MONO (-7438 862);
FORCEPROP 1 LASTPIN (-7250 850) $PN 2
J 0
(-7288 862);
DISPLAY 0.489362 (-7288 862);
PAINT MONO (-7288 862);
FORCEPROP 1 LAST WATTAGE 1/16W
J 2
(-7150 775);
DISPLAY 0.489362 (-7150 775);
PAINT SKYBLUE (-7150 775);
FORCEPROP 1 LAST MATERIAL CHIP
J 0
(-7250 800);
DISPLAY 0.489362 (-7250 800);
PAINT SKYBLUE (-7250 800);
FORCEPROP 1 LAST TOLERANCE 5%
J 0
(-7225 875);
DISPLAY 0.489362 (-7225 875);
PAINT SKYBLUE (-7225 875);
FORCEPROP 1 LAST VALUE 0
J 2
(-7475 875);
DISPLAY 0.489362 (-7475 875);
PAINT SKYBLUE (-7475 875);
FORCEPROP 1 LAST PART_NUMBER CS00002JB38
J 0
(-7625 800);
DISPLAY 0.489362 (-7625 800);
PAINT SKYBLUE (-7625 800);
FORCEPROP 1 LAST PACK_TYPE 0402LF
J 0
(-7250 900);
DISPLAY 0.489362 (-7250 900);
PAINT SKYBLUE (-7250 900);
FORCEPROP 2 LAST CDS_LIB pure_quanta
J 0
(-7350 850);
DISPLAY INVISIBLE (-7350 850);
FORCEPROP 1 LAST PATH I220
J 0
(-7400 1000);
DISPLAY 0.978723 (-7400 1000);
PAINT WHITE (-7400 1000);
DISPLAY INVISIBLE (-7400 1000);
FORCEADD VCC_CORE..1
(-7525 925);
FORCEPROP 3 LASTPIN (-7525 875) SIG_NAME P12V_STBY\g
J 0
(-7515 885);
DISPLAY 0.659574 (-7515 885);
PAINT MONO (-7515 885);
DISPLAY INVISIBLE (-7515 885);
FORCEPROP 1 LAST HDL_POWER P12V_STBY
J 1
(-7525 975);
DISPLAY 0.489362 (-7525 975);
PAINT GREEN (-7525 975);
FORCEPROP 2 LAST CDS_LIB pure_quanta_power
J 0
(-7525 925);
DISPLAY INVISIBLE (-7525 925);
FORCEPROP 1 LAST PATH I221
J 0
(-7475 950);
DISPLAY 0.872340 (-7475 950);
PAINT AQUA (-7475 950);
DISPLAY INVISIBLE (-7475 950);
FORCEADD VCC_CORE..1
(-8450 1375);
FORCEPROP 3 LASTPIN (-8450 1325) SIG_NAME P3V3_STBY\g
J 0
(-8440 1335);
DISPLAY 0.659574 (-8440 1335);
PAINT MONO (-8440 1335);
DISPLAY INVISIBLE (-8440 1335);
FORCEPROP 1 LAST HDL_POWER P3V3_STBY
J 1
(-8450 1425);
DISPLAY 0.489362 (-8450 1425);
PAINT GREEN (-8450 1425);
FORCEPROP 2 LAST CDS_LIB pure_quanta_power
J 0
(-8450 1375);
DISPLAY INVISIBLE (-8450 1375);
FORCEPROP 1 LAST PATH I222
J 0
(-8400 1400);
DISPLAY 0.872340 (-8400 1400);
PAINT AQUA (-8400 1400);
DISPLAY INVISIBLE (-8400 1400);
FORCEADD Q_RES..1
(-7975 1125);
FORCEPROP 1 LAST LOCATION PR66
J 0
(-8200 1125);
DISPLAY 0.489362 (-8200 1125);
PAINT SKYBLUE (-8200 1125);
FORCEPROP 0 LAST $SEC 1
J 0
(-8025 1225);
DISPLAY 0.680851 (-8025 1225);
PAINT MONO (-8025 1225);
DISPLAY INVISIBLE (-8025 1225);
FORCEPROP 0 LAST CDS_SEC 1
J 0
(-8025 1225);
DISPLAY 1.021277 (-8025 1225);
DISPLAY INVISIBLE (-8025 1225);
FORCEPROP 1 LASTPIN (-8075 1125) $PN 1
J 0
(-8063 1137);
DISPLAY 0.489362 (-8063 1137);
PAINT MONO (-8063 1137);
FORCEPROP 1 LASTPIN (-7875 1125) $PN 2
J 0
(-7913 1137);
DISPLAY 0.489362 (-7913 1137);
PAINT MONO (-7913 1137);
FORCEPROP 1 LAST WATTAGE 1/16W
J 2
(-7600 1225);
DISPLAY 0.489362 (-7600 1225);
PAINT SKYBLUE (-7600 1225);
FORCEPROP 1 LAST MATERIAL CHIP
J 0
(-7850 1225);
DISPLAY 0.489362 (-7850 1225);
PAINT SKYBLUE (-7850 1225);
FORCEPROP 1 LAST PACK_TYPE 0402LF
J 0
(-7725 1125);
DISPLAY 0.489362 (-7725 1125);
PAINT SKYBLUE (-7725 1125);
FORCEPROP 1 LAST PART_NUMBER CS00002JB38
J 0
(-7850 1175);
DISPLAY 0.489362 (-7850 1175);
PAINT SKYBLUE (-7850 1175);
FORCEPROP 1 LAST VALUE 0
J 2
(-7825 1125);
DISPLAY 0.489362 (-7825 1125);
PAINT SKYBLUE (-7825 1125);
FORCEPROP 1 LAST TOLERANCE 5%
J 0
(-7800 1125);
DISPLAY 0.489362 (-7800 1125);
PAINT SKYBLUE (-7800 1125);
FORCEPROP 1 LAST PATH I223
J 0
(-8025 1275);
DISPLAY 0.978723 (-8025 1275);
PAINT WHITE (-8025 1275);
DISPLAY INVISIBLE (-8025 1275);
FORCEPROP 2 LAST CDS_LIB pure_quanta
J 0
(-7975 1125);
DISPLAY INVISIBLE (-7975 1125);
FORCEADD Q_RES..1
(-7975 1275);
FORCEPROP 1 LAST LOCATION PR65
J 0
(-8200 1275);
DISPLAY 0.489362 (-8200 1275);
PAINT SKYBLUE (-8200 1275);
FORCEPROP 0 LAST $SEC 1
J 0
(-8025 1375);
DISPLAY 0.680851 (-8025 1375);
PAINT MONO (-8025 1375);
DISPLAY INVISIBLE (-8025 1375);
FORCEPROP 0 LAST CDS_SEC 1
J 0
(-8025 1375);
DISPLAY 1.021277 (-8025 1375);
DISPLAY INVISIBLE (-8025 1375);
FORCEPROP 1 LASTPIN (-8075 1275) $PN 1
J 0
(-8063 1287);
DISPLAY 0.489362 (-8063 1287);
PAINT MONO (-8063 1287);
FORCEPROP 1 LASTPIN (-7875 1275) $PN 2
J 0
(-7913 1287);
DISPLAY 0.489362 (-7913 1287);
PAINT MONO (-7913 1287);
FORCEPROP 1 LAST PACK_TYPE 0402LF
J 0
(-7675 1275);
DISPLAY 0.489362 (-7675 1275);
PAINT SKYBLUE (-7675 1275);
FORCEPROP 1 LAST WATTAGE 1/16W
J 2
(-7600 1375);
DISPLAY 0.489362 (-7600 1375);
PAINT SKYBLUE (-7600 1375);
FORCEPROP 1 LAST MATERIAL CHIP
J 0
(-7850 1375);
DISPLAY 0.489362 (-7850 1375);
PAINT SKYBLUE (-7850 1375);
FORCEPROP 1 LAST TOLERANCE 1%
J 0
(-7775 1275);
DISPLAY 0.489362 (-7775 1275);
PAINT SKYBLUE (-7775 1275);
FORCEPROP 1 LAST VALUE 1K
J 2
(-7800 1275);
DISPLAY 0.489362 (-7800 1275);
PAINT SKYBLUE (-7800 1275);
FORCEPROP 1 LAST PART_NUMBER TMP_QCS21002FB24
J 0
(-7850 1325);
DISPLAY 0.489362 (-7850 1325);
PAINT SKYBLUE (-7850 1325);
FORCEPROP 2 LAST CDS_LIB pure_quanta
J 0
(-7975 1275);
DISPLAY INVISIBLE (-7975 1275);
FORCEPROP 1 LAST PATH I224
J 0
(-8025 1425);
DISPLAY 0.978723 (-8025 1425);
PAINT WHITE (-8025 1425);
DISPLAY INVISIBLE (-8025 1425);
FORCEADD UNIVERSAL_GND..1
(-7800 550);
FORCEPROP 3 LASTPIN (-7800 600) SIG_NAME GND\g
J 0
(-7790 610);
DISPLAY 0.659574 (-7790 610);
PAINT MONO (-7790 610);
DISPLAY INVISIBLE (-7790 610);
FORCEPROP 2 LAST CDS_LIB pure_quanta_power
J 0
(-7800 550);
PAINT MONO (-7800 550);
DISPLAY INVISIBLE (-7800 550);
FORCEPROP 1 LAST PATH I226
J 0
(-7725 550);
DISPLAY 0.872340 (-7725 550);
PAINT AQUA (-7725 550);
DISPLAY INVISIBLE (-7725 550);
FORCEPROP 1 LAST HDL_POWER GND
J 1
(-7775 475);
DISPLAY 0.872340 (-7775 475);
PAINT GREEN (-7775 475);
DISPLAY INVISIBLE (-7775 475);
FORCEADD Q_RES..2
(-8250 850);
FORCEPROP 1 LAST LOCATION PR54
J 0
(-8205 975);
DISPLAY 0.489362 (-8205 975);
PAINT SKYBLUE (-8205 975);
FORCEPROP 0 LAST $SEC 1
J 0
(-8200 1025);
DISPLAY 0.680851 (-8200 1025);
PAINT MONO (-8200 1025);
DISPLAY INVISIBLE (-8200 1025);
FORCEPROP 0 LAST CDS_SEC 1
J 0
(-8200 1025);
DISPLAY 1.021277 (-8200 1025);
DISPLAY INVISIBLE (-8200 1025);
FORCEPROP 1 LASTPIN (-8250 950) $PN 1
J 0
(-8245 912);
DISPLAY 0.489362 (-8245 912);
PAINT MONO (-8245 912);
FORCEPROP 1 LASTPIN (-8250 750) $PN 2
J 0
(-8245 760);
DISPLAY 0.489362 (-8245 760);
PAINT MONO (-8245 760);
FORCEPROP 1 LAST PART_NUMBER TMP_QCS31002FB26
J 0
(-8210 725);
DISPLAY 0.489362 (-8210 725);
PAINT SKYBLUE (-8210 725);
FORCEPROP 1 LAST PACK_TYPE 0402LF
J 0
(-8210 675);
DISPLAY 0.489362 (-8210 675);
PAINT SKYBLUE (-8210 675);
FORCEPROP 1 LAST WATTAGE 1/16W
J 0
(-8210 825);
DISPLAY 0.489362 (-8210 825);
PAINT SKYBLUE (-8210 825);
FORCEPROP 1 LAST MATERIAL CHIP
J 0
(-8210 775);
DISPLAY 0.489362 (-8210 775);
PAINT SKYBLUE (-8210 775);
FORCEPROP 1 LAST TOLERANCE 1%
J 0
(-8205 875);
DISPLAY 0.489362 (-8205 875);
PAINT SKYBLUE (-8205 875);
FORCEPROP 1 LAST VALUE 10K
J 0
(-8205 925);
DISPLAY 0.489362 (-8205 925);
PAINT SKYBLUE (-8205 925);
FORCEPROP 2 LAST CDS_LIB pure_quanta
J 0
(-8250 850);
DISPLAY INVISIBLE (-8250 850);
FORCEPROP 1 LAST PATH I227
J 0
(-8200 1025);
DISPLAY 0.978723 (-8200 1025);
PAINT WHITE (-8200 1025);
DISPLAY INVISIBLE (-8200 1025);
FORCEADD Q_CAP..1
(-7800 875);
FORCEPROP 1 LAST LOCATION PC67
J 0
(-7750 1000);
DISPLAY 0.489362 (-7750 1000);
PAINT SKYBLUE (-7750 1000);
FORCEPROP 0 LAST $SEC 1
J 0
(-7750 1050);
DISPLAY 0.680851 (-7750 1050);
PAINT MONO (-7750 1050);
DISPLAY INVISIBLE (-7750 1050);
FORCEPROP 0 LAST CDS_SEC 1
J 0
(-7750 1050);
DISPLAY 1.021277 (-7750 1050);
DISPLAY INVISIBLE (-7750 1050);
FORCEPROP 1 LASTPIN (-7800 975) $PN 1
J 0
(-7790 955);
DISPLAY 0.489362 (-7790 955);
PAINT MONO (-7790 955);
FORCEPROP 1 LASTPIN (-7800 775) $PN 2
J 0
(-7790 755);
DISPLAY 0.489362 (-7790 755);
PAINT MONO (-7790 755);
FORCEPROP 1 LAST MATERIAL X7R
J 0
(-7750 800);
DISPLAY 0.489362 (-7750 800);
PAINT SKYBLUE (-7750 800);
FORCEPROP 1 LAST TOLERANCE 10%
J 0
(-7750 850);
DISPLAY 0.489362 (-7750 850);
PAINT SKYBLUE (-7750 850);
FORCEPROP 1 LAST VALUE 0.1UF
J 0
(-7750 950);
DISPLAY 0.489362 (-7750 950);
PAINT SKYBLUE (-7750 950);
FORCEPROP 1 LAST PART_NUMBER CH4104K1B00
J 0
(-7750 700);
DISPLAY 0.489362 (-7750 700);
PAINT SKYBLUE (-7750 700);
FORCEPROP 1 LAST VOLTAGE 25V
J 0
(-7750 900);
DISPLAY 0.489362 (-7750 900);
PAINT SKYBLUE (-7750 900);
FORCEPROP 1 LAST PACK_TYPE 0402
J 0
(-7750 750);
DISPLAY 0.489362 (-7750 750);
PAINT SKYBLUE (-7750 750);
FORCEPROP 2 LAST CDS_LIB pure_quanta
J 0
(-7800 875);
DISPLAY INVISIBLE (-7800 875);
FORCEPROP 1 LAST PATH I228
J 0
(-7750 1025);
DISPLAY 0.978723 (-7750 1025);
PAINT WHITE (-7750 1025);
DISPLAY INVISIBLE (-7750 1025);
FORCEADD Q_CAP..2
(-7175 1275);
FORCEPROP 1 LAST LOCATION PC72
J 1
(-7375 1275);
DISPLAY 0.489362 (-7375 1275);
PAINT SKYBLUE (-7375 1275);
FORCEPROP 0 LAST $SEC 1
J 0
(-7225 1375);
DISPLAY 0.680851 (-7225 1375);
PAINT MONO (-7225 1375);
DISPLAY INVISIBLE (-7225 1375);
FORCEPROP 0 LAST CDS_SEC 1
J 0
(-7225 1375);
DISPLAY 1.021277 (-7225 1375);
DISPLAY INVISIBLE (-7225 1375);
FORCEPROP 1 LASTPIN (-7275 1275) $PN 1
J 0
(-7285 1290);
DISPLAY 0.489362 (-7285 1290);
PAINT MONO (-7285 1290);
FORCEPROP 1 LASTPIN (-7075 1275) $PN 2
J 0
(-7090 1290);
DISPLAY 0.489362 (-7090 1290);
PAINT MONO (-7090 1290);
FORCEPROP 1 LAST PART_NUMBER TMP_QCH21006JB10
J 1
(-6900 1225);
DISPLAY 0.489362 (-6900 1225);
PAINT SKYBLUE (-6900 1225);
FORCEPROP 1 LAST MATERIAL EMPTY
J 0
(-6700 1275);
DISPLAY 0.489362 (-6700 1275);
PAINT RED (-6700 1275);
FORCEPROP 1 LAST TOLERANCE 5%
J 2
(-6525 1225);
DISPLAY 0.489362 (-6525 1225);
PAINT SKYBLUE (-6525 1225);
FORCEPROP 1 LAST VALUE 1000PF
J 2
(-6850 1275);
DISPLAY 0.489362 (-6850 1275);
PAINT SKYBLUE (-6850 1275);
FORCEPROP 1 LAST VOLTAGE 50V
J 0
(-6825 1275);
DISPLAY 0.489362 (-6825 1275);
PAINT SKYBLUE (-6825 1275);
FORCEPROP 1 LAST PACK_TYPE 0402
J 1
(-6675 1225);
DISPLAY 0.489362 (-6675 1225);
PAINT SKYBLUE (-6675 1225);
FORCEPROP 2 LAST CDS_LIB pure_quanta
J 0
(-7175 1275);
DISPLAY INVISIBLE (-7175 1275);
FORCEPROP 1 LAST PATH I230
J 0
(-7175 1475);
DISPLAY 0.978723 (-7175 1475);
PAINT WHITE (-7175 1475);
DISPLAY INVISIBLE (-7175 1475);
FORCEADD Q_RES..1
(-8750 2750);
FORCEPROP 1 LAST LOCATION PR50
J 0
(-8950 2750);
DISPLAY 0.489362 (-8950 2750);
PAINT SKYBLUE (-8950 2750);
FORCEPROP 2 LAST $SEC 1
J 0
(-8800 2950);
DISPLAY 0.680851 (-8800 2950);
PAINT MONO (-8800 2950);
DISPLAY INVISIBLE (-8800 2950);
FORCEPROP 2 LAST CDS_SEC 1
J 0
(-8800 2950);
DISPLAY 1.021277 (-8800 2950);
DISPLAY INVISIBLE (-8800 2950);
FORCEPROP 1 LASTPIN (-8850 2750) $PN 1
J 0
(-8838 2762);
DISPLAY 0.489362 (-8838 2762);
FORCEPROP 1 LASTPIN (-8650 2750) $PN 2
J 0
(-8688 2762);
DISPLAY 0.489362 (-8688 2762);
FORCEPROP 1 LAST MATERIAL CHIP
J 0
(-8625 2850);
DISPLAY 0.489362 (-8625 2850);
PAINT SKYBLUE (-8625 2850);
FORCEPROP 1 LAST PART_NUMBER CS04992FB31
J 0
(-8625 2800);
DISPLAY 0.489362 (-8625 2800);
PAINT SKYBLUE (-8625 2800);
FORCEPROP 1 LAST PACK_TYPE 0402LF
J 0
(-8450 2750);
DISPLAY 0.489362 (-8450 2750);
PAINT SKYBLUE (-8450 2750);
FORCEPROP 1 LAST WATTAGE 1/16W
J 2
(-8375 2850);
DISPLAY 0.489362 (-8375 2850);
PAINT SKYBLUE (-8375 2850);
FORCEPROP 1 LAST VALUE 49.9
J 2
(-8575 2800);
DISPLAY 0.489362 (-8575 2800);
PAINT SKYBLUE (-8575 2800);
FORCEPROP 1 LAST TOLERANCE 1%
J 0
(-8525 2750);
DISPLAY 0.489362 (-8525 2750);
PAINT SKYBLUE (-8525 2750);
FORCEPROP 2 LAST CDS_LIB pure_quanta
J 0
(-8750 2750);
PAINT MONO (-8750 2750);
DISPLAY INVISIBLE (-8750 2750);
FORCEPROP 1 LAST PATH I233
J 0
(-8800 2900);
DISPLAY 0.978723 (-8800 2900);
PAINT WHITE (-8800 2900);
DISPLAY INVISIBLE (-8800 2900);
FORCEADD UNIVERSAL_GND..1
(-8225 2650);
FORCEPROP 3 LASTPIN (-8225 2700) SIG_NAME GND\g
J 0
(-8215 2710);
DISPLAY 0.659574 (-8215 2710);
PAINT MONO (-8215 2710);
DISPLAY INVISIBLE (-8215 2710);
FORCEPROP 2 LAST CDS_LIB pure_quanta_power
J 0
(-8225 2650);
PAINT MONO (-8225 2650);
DISPLAY INVISIBLE (-8225 2650);
FORCEPROP 1 LAST PATH I238
J 0
(-8150 2650);
DISPLAY 0.872340 (-8150 2650);
PAINT AQUA (-8150 2650);
DISPLAY INVISIBLE (-8150 2650);
FORCEPROP 1 LAST HDL_POWER GND
J 1
(-8200 2575);
DISPLAY 0.872340 (-8200 2575);
PAINT GREEN (-8200 2575);
DISPLAY INVISIBLE (-8200 2575);
FORCEADD Q_RES..1
(-8700 3425);
FORCEPROP 1 LAST LOCATION PR52
J 0
(-8900 3425);
DISPLAY 0.489362 (-8900 3425);
PAINT SKYBLUE (-8900 3425);
FORCEPROP 2 LAST $SEC 1
J 0
(-8750 3625);
DISPLAY 0.680851 (-8750 3625);
PAINT MONO (-8750 3625);
DISPLAY INVISIBLE (-8750 3625);
FORCEPROP 2 LAST CDS_SEC 1
J 0
(-8750 3625);
DISPLAY 1.021277 (-8750 3625);
DISPLAY INVISIBLE (-8750 3625);
FORCEPROP 1 LASTPIN (-8800 3425) $PN 1
J 0
(-8788 3437);
DISPLAY 0.489362 (-8788 3437);
FORCEPROP 1 LASTPIN (-8600 3425) $PN 2
J 0
(-8638 3437);
DISPLAY 0.489362 (-8638 3437);
FORCEPROP 1 LAST WATTAGE 1/16W
J 2
(-8325 3525);
DISPLAY 0.489362 (-8325 3525);
PAINT SKYBLUE (-8325 3525);
FORCEPROP 1 LAST MATERIAL CHIP
J 0
(-8575 3525);
DISPLAY 0.489362 (-8575 3525);
PAINT SKYBLUE (-8575 3525);
FORCEPROP 1 LAST PART_NUMBER CS04992FB31
J 0
(-8575 3475);
DISPLAY 0.489362 (-8575 3475);
PAINT SKYBLUE (-8575 3475);
FORCEPROP 1 LAST PACK_TYPE 0402LF
J 0
(-8400 3425);
DISPLAY 0.489362 (-8400 3425);
PAINT SKYBLUE (-8400 3425);
FORCEPROP 1 LAST VALUE 49.9
J 2
(-8525 3475);
DISPLAY 0.489362 (-8525 3475);
PAINT SKYBLUE (-8525 3475);
FORCEPROP 1 LAST TOLERANCE 1%
J 0
(-8475 3425);
DISPLAY 0.489362 (-8475 3425);
PAINT SKYBLUE (-8475 3425);
FORCEPROP 2 LAST CDS_LIB pure_quanta
J 0
(-8700 3425);
PAINT MONO (-8700 3425);
DISPLAY INVISIBLE (-8700 3425);
FORCEPROP 1 LAST PATH I239
J 0
(-8750 3575);
DISPLAY 0.978723 (-8750 3575);
PAINT WHITE (-8750 3575);
DISPLAY INVISIBLE (-8750 3575);
FORCEADD Q_RES..1
(-8750 3850);
FORCEPROP 1 LAST LOCATION PR49
J 0
(-8950 3850);
DISPLAY 0.489362 (-8950 3850);
PAINT SKYBLUE (-8950 3850);
FORCEPROP 2 LAST $SEC 1
J 0
(-8800 4050);
DISPLAY 0.680851 (-8800 4050);
PAINT MONO (-8800 4050);
DISPLAY INVISIBLE (-8800 4050);
FORCEPROP 2 LAST CDS_SEC 1
J 0
(-8800 4050);
DISPLAY 1.021277 (-8800 4050);
DISPLAY INVISIBLE (-8800 4050);
FORCEPROP 1 LASTPIN (-8850 3850) $PN 1
J 0
(-8838 3862);
DISPLAY 0.489362 (-8838 3862);
FORCEPROP 1 LASTPIN (-8650 3850) $PN 2
J 0
(-8688 3862);
DISPLAY 0.489362 (-8688 3862);
FORCEPROP 1 LAST WATTAGE 1/16W
J 2
(-8375 3950);
DISPLAY 0.489362 (-8375 3950);
PAINT SKYBLUE (-8375 3950);
FORCEPROP 1 LAST MATERIAL CHIP
J 0
(-8625 3950);
DISPLAY 0.489362 (-8625 3950);
PAINT SKYBLUE (-8625 3950);
FORCEPROP 1 LAST PART_NUMBER CS04992FB31
J 0
(-8625 3900);
DISPLAY 0.489362 (-8625 3900);
PAINT SKYBLUE (-8625 3900);
FORCEPROP 1 LAST PACK_TYPE 0402LF
J 0
(-8450 3850);
DISPLAY 0.489362 (-8450 3850);
PAINT SKYBLUE (-8450 3850);
FORCEPROP 1 LAST VALUE 49.9
J 2
(-8575 3900);
DISPLAY 0.489362 (-8575 3900);
PAINT SKYBLUE (-8575 3900);
FORCEPROP 1 LAST TOLERANCE 1%
J 0
(-8525 3850);
DISPLAY 0.489362 (-8525 3850);
PAINT SKYBLUE (-8525 3850);
FORCEPROP 2 LAST CDS_LIB pure_quanta
J 0
(-8750 3850);
PAINT MONO (-8750 3850);
DISPLAY INVISIBLE (-8750 3850);
FORCEPROP 1 LAST PATH I240
J 0
(-8800 4000);
DISPLAY 0.978723 (-8800 4000);
PAINT WHITE (-8800 4000);
DISPLAY INVISIBLE (-8800 4000);
FORCEADD VCC_CORE..1
(-8200 3575);
FORCEPROP 3 LASTPIN (-8200 3525) SIG_NAME PVDDIO_P0\g
J 0
(-8190 3535);
DISPLAY 0.659574 (-8190 3535);
PAINT MONO (-8190 3535);
DISPLAY INVISIBLE (-8190 3535);
FORCEPROP 1 LAST HDL_POWER PVDDIO_P0
J 1
(-8200 3625);
DISPLAY 0.489362 (-8200 3625);
PAINT GREEN (-8200 3625);
FORCEPROP 2 LAST CDS_LIB pure_quanta_power
J 0
(-8200 3575);
DISPLAY INVISIBLE (-8200 3575);
FORCEPROP 1 LAST PATH I241
J 0
(-8150 3600);
DISPLAY 0.872340 (-8150 3600);
PAINT AQUA (-8150 3600);
DISPLAY INVISIBLE (-8150 3600);
FORCEADD UNIVERSAL_GND..1
(-8225 3750);
FORCEPROP 3 LASTPIN (-8225 3800) SIG_NAME GND\g
J 0
(-8215 3810);
DISPLAY 0.659574 (-8215 3810);
PAINT MONO (-8215 3810);
DISPLAY INVISIBLE (-8215 3810);
FORCEPROP 2 LAST CDS_LIB pure_quanta_power
J 0
(-8225 3750);
PAINT MONO (-8225 3750);
DISPLAY INVISIBLE (-8225 3750);
FORCEPROP 1 LAST PATH I242
J 0
(-8150 3750);
DISPLAY 0.872340 (-8150 3750);
PAINT AQUA (-8150 3750);
DISPLAY INVISIBLE (-8150 3750);
FORCEPROP 1 LAST HDL_POWER GND
J 1
(-8200 3675);
DISPLAY 0.872340 (-8200 3675);
PAINT GREEN (-8200 3675);
DISPLAY INVISIBLE (-8200 3675);
FORCEADD Q_CAP..1
(-7225 3100);
FORCEPROP 1 LAST LOCATION PC71
J 0
(-7175 3225);
DISPLAY 0.489362 (-7175 3225);
PAINT SKYBLUE (-7175 3225);
FORCEPROP 0 LAST $SEC 1
J 0
(-7175 3225);
DISPLAY 0.680851 (-7175 3225);
PAINT MONO (-7175 3225);
DISPLAY INVISIBLE (-7175 3225);
FORCEPROP 0 LAST CDS_SEC 1
J 0
(-7175 3225);
DISPLAY 1.021277 (-7175 3225);
DISPLAY INVISIBLE (-7175 3225);
FORCEPROP 1 LASTPIN (-7225 3200) $PN 1
J 0
(-7215 3180);
DISPLAY 0.489362 (-7215 3180);
PAINT MONO (-7215 3180);
FORCEPROP 1 LASTPIN (-7225 3000) $PN 2
J 0
(-7215 2980);
DISPLAY 0.489362 (-7215 2980);
PAINT MONO (-7215 2980);
FORCEPROP 1 LAST MATERIAL X7R
J 0
(-7175 3025);
DISPLAY 0.489362 (-7175 3025);
PAINT SKYBLUE (-7175 3025);
FORCEPROP 1 LAST TOLERANCE 10%
J 0
(-7175 3075);
DISPLAY 0.489362 (-7175 3075);
PAINT SKYBLUE (-7175 3075);
FORCEPROP 1 LAST VALUE 3300PF
J 0
(-7175 3175);
DISPLAY 0.489362 (-7175 3175);
PAINT SKYBLUE (-7175 3175);
FORCEPROP 1 LAST PART_NUMBER TMP_QCH2336K1B12
J 0
(-7175 2925);
DISPLAY 0.489362 (-7175 2925);
PAINT SKYBLUE (-7175 2925);
FORCEPROP 1 LAST VOLTAGE 50V
J 0
(-7175 3125);
DISPLAY 0.489362 (-7175 3125);
PAINT SKYBLUE (-7175 3125);
FORCEPROP 1 LAST PACK_TYPE 0402
J 0
(-7175 2975);
DISPLAY 0.489362 (-7175 2975);
PAINT SKYBLUE (-7175 2975);
FORCEPROP 2 LAST CDS_LIB pure_quanta
J 0
(-7225 3100);
DISPLAY INVISIBLE (-7225 3100);
FORCEPROP 1 LAST PATH I245
J 0
(-7175 3250);
DISPLAY 0.978723 (-7175 3250);
PAINT WHITE (-7175 3250);
DISPLAY INVISIBLE (-7175 3250);
FORCEADD Q_RES..1
(-7675 3275);
FORCEPROP 1 LAST LOCATION PR69
J 0
(-7875 3275);
DISPLAY 0.489362 (-7875 3275);
PAINT SKYBLUE (-7875 3275);
FORCEPROP 0 LAST $SEC 1
J 0
(-7725 3375);
DISPLAY 0.680851 (-7725 3375);
PAINT MONO (-7725 3375);
DISPLAY INVISIBLE (-7725 3375);
FORCEPROP 0 LAST CDS_SEC 1
J 0
(-7725 3375);
DISPLAY 1.021277 (-7725 3375);
DISPLAY INVISIBLE (-7725 3375);
FORCEPROP 1 LASTPIN (-7775 3275) $PN 1
J 0
(-7763 3287);
DISPLAY 0.489362 (-7763 3287);
PAINT MONO (-7763 3287);
FORCEPROP 1 LASTPIN (-7575 3275) $PN 2
J 0
(-7613 3287);
DISPLAY 0.489362 (-7613 3287);
PAINT MONO (-7613 3287);
FORCEPROP 1 LAST WATTAGE 1/16W
J 2
(-7300 3375);
DISPLAY 0.489362 (-7300 3375);
PAINT SKYBLUE (-7300 3375);
FORCEPROP 1 LAST MATERIAL CHIP
J 0
(-7550 3375);
DISPLAY 0.489362 (-7550 3375);
PAINT SKYBLUE (-7550 3375);
FORCEPROP 1 LAST TOLERANCE 5%
J 0
(-7500 3275);
DISPLAY 0.489362 (-7500 3275);
PAINT SKYBLUE (-7500 3275);
FORCEPROP 1 LAST VALUE 10
J 2
(-7525 3275);
DISPLAY 0.489362 (-7525 3275);
PAINT SKYBLUE (-7525 3275);
FORCEPROP 1 LAST PART_NUMBER TMP_QCS01002JB22
J 0
(-7550 3325);
DISPLAY 0.489362 (-7550 3325);
PAINT SKYBLUE (-7550 3325);
FORCEPROP 1 LAST PACK_TYPE 0402LF
J 0
(-7425 3275);
DISPLAY 0.489362 (-7425 3275);
PAINT SKYBLUE (-7425 3275);
FORCEPROP 2 LAST CDS_LIB pure_quanta
J 0
(-7675 3275);
DISPLAY INVISIBLE (-7675 3275);
FORCEPROP 1 LAST PATH I246
J 0
(-7725 3425);
DISPLAY 0.978723 (-7725 3425);
PAINT WHITE (-7725 3425);
DISPLAY INVISIBLE (-7725 3425);
FORCEADD Q_CAP..1
(-7275 4200);
FORCEPROP 1 LAST LOCATION PC68
J 0
(-7225 4325);
DISPLAY 0.489362 (-7225 4325);
PAINT SKYBLUE (-7225 4325);
FORCEPROP 0 LAST $SEC 1
J 0
(-7225 4325);
DISPLAY 0.680851 (-7225 4325);
PAINT MONO (-7225 4325);
DISPLAY INVISIBLE (-7225 4325);
FORCEPROP 0 LAST CDS_SEC 1
J 0
(-7225 4325);
DISPLAY 1.021277 (-7225 4325);
DISPLAY INVISIBLE (-7225 4325);
FORCEPROP 1 LASTPIN (-7275 4300) $PN 1
J 0
(-7265 4280);
DISPLAY 0.489362 (-7265 4280);
PAINT MONO (-7265 4280);
FORCEPROP 1 LASTPIN (-7275 4100) $PN 2
J 0
(-7265 4080);
DISPLAY 0.489362 (-7265 4080);
PAINT MONO (-7265 4080);
FORCEPROP 1 LAST MATERIAL X7R
J 0
(-7225 4125);
DISPLAY 0.489362 (-7225 4125);
PAINT SKYBLUE (-7225 4125);
FORCEPROP 1 LAST TOLERANCE 10%
J 0
(-7225 4175);
DISPLAY 0.489362 (-7225 4175);
PAINT SKYBLUE (-7225 4175);
FORCEPROP 1 LAST VALUE 3300PF
J 0
(-7225 4275);
DISPLAY 0.489362 (-7225 4275);
PAINT SKYBLUE (-7225 4275);
FORCEPROP 1 LAST PART_NUMBER TMP_QCH2336K1B12
J 0
(-7225 4025);
DISPLAY 0.489362 (-7225 4025);
PAINT SKYBLUE (-7225 4025);
FORCEPROP 1 LAST VOLTAGE 50V
J 0
(-7225 4225);
DISPLAY 0.489362 (-7225 4225);
PAINT SKYBLUE (-7225 4225);
FORCEPROP 1 LAST PACK_TYPE 0402
J 0
(-7225 4075);
DISPLAY 0.489362 (-7225 4075);
PAINT SKYBLUE (-7225 4075);
FORCEPROP 2 LAST CDS_LIB pure_quanta
J 0
(-7275 4200);
DISPLAY INVISIBLE (-7275 4200);
FORCEPROP 1 LAST PATH I247
J 0
(-7225 4350);
DISPLAY 0.978723 (-7225 4350);
PAINT WHITE (-7225 4350);
DISPLAY INVISIBLE (-7225 4350);
FORCEADD OFFPAGE..1
(-9950 4375);
FORCEPROP 2 LAST $XR0 27 
J 0
(-10231 4375);
DISPLAY 0.638298 (-10231 4375);
PAINT MONO (-10231 4375);
FORCEPROP 2 LAST PATH I248
J 0
(-10225 4425);
DISPLAY 1.021277 (-10225 4425);
DISPLAY INVISIBLE (-10225 4425);
FORCEPROP 1 LAST COMMENT_BODY TRUE
J 0
(-9825 4275);
DISPLAY 0.872340 (-9825 4275);
PAINT GREEN (-9825 4275);
DISPLAY INVISIBLE (-9825 4275);
FORCEPROP 1 LAST OFFPAGE TRUE
J 0
(-9625 4250);
DISPLAY 0.872340 (-9625 4250);
PAINT GREEN (-9625 4250);
DISPLAY INVISIBLE (-9625 4250);
FORCEPROP 2 LAST CDS_LIB standard
J 0
(-9950 4375);
DISPLAY INVISIBLE (-9950 4375);
FORCEADD OFFPAGE..6
(-8400 5075);
FORCEPROP 2 LAST $XR1 200 
J 0
(-8800 5075);
DISPLAY 0.638298 (-8800 5075);
PAINT MONO (-8800 5075);
FORCEPROP 2 LAST $XR0 118 
J 0
(-8680 5075);
DISPLAY 0.638298 (-8680 5075);
PAINT MONO (-8680 5075);
FORCEPROP 2 LAST PATH I253
J 0
(-8675 5125);
DISPLAY 1.021277 (-8675 5125);
DISPLAY INVISIBLE (-8675 5125);
FORCEPROP 1 LAST COMMENT_BODY TRUE
J 0
(-8300 5000);
DISPLAY 0.872340 (-8300 5000);
PAINT GREEN (-8300 5000);
DISPLAY INVISIBLE (-8300 5000);
FORCEPROP 1 LAST OFFPAGE TRUE
J 0
(-8075 4950);
DISPLAY 0.872340 (-8075 4950);
PAINT GREEN (-8075 4950);
DISPLAY INVISIBLE (-8075 4950);
FORCEPROP 2 LAST CDS_LIB standard
J 0
(-8400 5075);
DISPLAY INVISIBLE (-8400 5075);
FORCEADD OFFPAGE..1
(-8400 5225);
FORCEPROP 2 LAST $XR1 200 
J 0
(-8772 5225);
DISPLAY 0.638298 (-8772 5225);
PAINT MONO (-8772 5225);
FORCEPROP 2 LAST $XR0 118 
J 0
(-8652 5225);
DISPLAY 0.638298 (-8652 5225);
PAINT MONO (-8652 5225);
FORCEPROP 2 LAST PATH I254
J 0
(-8650 5275);
DISPLAY 1.021277 (-8650 5275);
DISPLAY INVISIBLE (-8650 5275);
FORCEPROP 1 LAST COMMENT_BODY TRUE
J 0
(-8275 5125);
DISPLAY 0.872340 (-8275 5125);
PAINT GREEN (-8275 5125);
DISPLAY INVISIBLE (-8275 5125);
FORCEPROP 1 LAST OFFPAGE TRUE
J 0
(-8075 5100);
DISPLAY 0.872340 (-8075 5100);
PAINT GREEN (-8075 5100);
DISPLAY INVISIBLE (-8075 5100);
FORCEPROP 2 LAST CDS_LIB standard
J 0
(-8400 5225);
DISPLAY INVISIBLE (-8400 5225);
FORCEADD OFFPAGE..1
(-8875 6225);
FORCEPROP 2 LAST $XR0 81 
J 0
(-9096 6225);
DISPLAY 0.638298 (-9096 6225);
PAINT MONO (-9096 6225);
FORCEPROP 2 LAST CDS_LIB standard
J 0
(-8875 6225);
DISPLAY INVISIBLE (-8875 6225);
FORCEPROP 1 LAST OFFPAGE TRUE
J 0
(-8550 6100);
DISPLAY 0.872340 (-8550 6100);
PAINT GREEN (-8550 6100);
DISPLAY INVISIBLE (-8550 6100);
FORCEPROP 1 LAST COMMENT_BODY TRUE
J 0
(-8750 6125);
DISPLAY 0.872340 (-8750 6125);
PAINT GREEN (-8750 6125);
DISPLAY INVISIBLE (-8750 6125);
FORCEPROP 2 LAST PATH I259
J 0
(-9125 6275);
DISPLAY 1.021277 (-9125 6275);
DISPLAY INVISIBLE (-9125 6275);
FORCEADD OFFPAGE..5
(-8875 6375);
FORCEPROP 2 LAST $XR0 81 
J 0
(-9099 6375);
DISPLAY 0.638298 (-9099 6375);
PAINT MONO (-9099 6375);
FORCEPROP 2 LAST CDS_LIB standard
J 0
(-8875 6375);
DISPLAY INVISIBLE (-8875 6375);
FORCEPROP 1 LAST OFFPAGE TRUE
J 0
(-8550 6250);
DISPLAY 0.872340 (-8550 6250);
PAINT GREEN (-8550 6250);
DISPLAY INVISIBLE (-8550 6250);
FORCEPROP 1 LAST COMMENT_BODY TRUE
J 0
(-8775 6300);
DISPLAY 0.872340 (-8775 6300);
PAINT GREEN (-8775 6300);
DISPLAY INVISIBLE (-8775 6300);
FORCEPROP 2 LAST PATH I260
J 0
(-9125 6425);
DISPLAY 1.021277 (-9125 6425);
DISPLAY INVISIBLE (-9125 6425);
FORCEADD Q_RES..1
(-8700 4525);
FORCEPROP 1 LAST LOCATION PR51
J 0
(-8900 4525);
DISPLAY 0.489362 (-8900 4525);
PAINT SKYBLUE (-8900 4525);
FORCEPROP 2 LAST $SEC 1
J 0
(-8750 4725);
DISPLAY 0.680851 (-8750 4725);
PAINT MONO (-8750 4725);
DISPLAY INVISIBLE (-8750 4725);
FORCEPROP 2 LAST CDS_SEC 1
J 0
(-8750 4725);
DISPLAY 1.021277 (-8750 4725);
DISPLAY INVISIBLE (-8750 4725);
FORCEPROP 1 LASTPIN (-8800 4525) $PN 1
J 0
(-8788 4537);
DISPLAY 0.489362 (-8788 4537);
FORCEPROP 1 LASTPIN (-8600 4525) $PN 2
J 0
(-8638 4537);
DISPLAY 0.489362 (-8638 4537);
FORCEPROP 1 LAST PACK_TYPE 0402LF
J 0
(-8400 4525);
DISPLAY 0.489362 (-8400 4525);
PAINT SKYBLUE (-8400 4525);
FORCEPROP 1 LAST PART_NUMBER CS04992FB31
J 0
(-8575 4575);
DISPLAY 0.489362 (-8575 4575);
PAINT SKYBLUE (-8575 4575);
FORCEPROP 1 LAST WATTAGE 1/16W
J 2
(-8325 4625);
DISPLAY 0.489362 (-8325 4625);
PAINT SKYBLUE (-8325 4625);
FORCEPROP 1 LAST MATERIAL CHIP
J 0
(-8575 4625);
DISPLAY 0.489362 (-8575 4625);
PAINT SKYBLUE (-8575 4625);
FORCEPROP 1 LAST VALUE 49.9
J 2
(-8525 4575);
DISPLAY 0.489362 (-8525 4575);
PAINT SKYBLUE (-8525 4575);
FORCEPROP 1 LAST TOLERANCE 1%
J 0
(-8475 4525);
DISPLAY 0.489362 (-8475 4525);
PAINT SKYBLUE (-8475 4525);
FORCEPROP 2 LAST CDS_LIB pure_quanta
J 0
(-8700 4525);
PAINT MONO (-8700 4525);
DISPLAY INVISIBLE (-8700 4525);
FORCEPROP 1 LAST PATH I261
J 0
(-8750 4675);
DISPLAY 0.978723 (-8750 4675);
PAINT WHITE (-8750 4675);
DISPLAY INVISIBLE (-8750 4675);
FORCEADD VCC_CORE..1
(-8025 4675);
FORCEPROP 3 LASTPIN (-8025 4625) SIG_NAME PVDDCR_CPU1_P0\g
J 0
(-8015 4635);
DISPLAY 0.659574 (-8015 4635);
PAINT MONO (-8015 4635);
DISPLAY INVISIBLE (-8015 4635);
FORCEPROP 1 LAST HDL_POWER PVDDCR_CPU1_P0
J 1
(-8025 4725);
DISPLAY 0.489362 (-8025 4725);
PAINT GREEN (-8025 4725);
FORCEPROP 2 LAST CDS_LIB pure_quanta_power
J 0
(-8025 4675);
DISPLAY INVISIBLE (-8025 4675);
FORCEPROP 1 LAST PATH I264
J 0
(-7975 4700);
DISPLAY 0.872340 (-7975 4700);
PAINT AQUA (-7975 4700);
DISPLAY INVISIBLE (-7975 4700);
FORCEADD Q_RES..1
(-7725 4375);
FORCEPROP 1 LAST LOCATION PR68
J 0
(-7925 4375);
DISPLAY 0.489362 (-7925 4375);
PAINT SKYBLUE (-7925 4375);
FORCEPROP 0 LAST $SEC 1
J 0
(-7775 4475);
DISPLAY 0.680851 (-7775 4475);
PAINT MONO (-7775 4475);
DISPLAY INVISIBLE (-7775 4475);
FORCEPROP 0 LAST CDS_SEC 1
J 0
(-7775 4475);
DISPLAY 1.021277 (-7775 4475);
DISPLAY INVISIBLE (-7775 4475);
FORCEPROP 1 LASTPIN (-7825 4375) $PN 1
J 0
(-7813 4387);
DISPLAY 0.489362 (-7813 4387);
PAINT MONO (-7813 4387);
FORCEPROP 1 LASTPIN (-7625 4375) $PN 2
J 0
(-7663 4387);
DISPLAY 0.489362 (-7663 4387);
PAINT MONO (-7663 4387);
FORCEPROP 1 LAST WATTAGE 1/16W
J 2
(-7350 4475);
DISPLAY 0.489362 (-7350 4475);
PAINT SKYBLUE (-7350 4475);
FORCEPROP 1 LAST MATERIAL CHIP
J 0
(-7600 4475);
DISPLAY 0.489362 (-7600 4475);
PAINT SKYBLUE (-7600 4475);
FORCEPROP 1 LAST TOLERANCE 5%
J 0
(-7550 4375);
DISPLAY 0.489362 (-7550 4375);
PAINT SKYBLUE (-7550 4375);
FORCEPROP 1 LAST VALUE 10
J 2
(-7575 4375);
DISPLAY 0.489362 (-7575 4375);
PAINT SKYBLUE (-7575 4375);
FORCEPROP 1 LAST PART_NUMBER TMP_QCS01002JB22
J 0
(-7600 4425);
DISPLAY 0.489362 (-7600 4425);
PAINT SKYBLUE (-7600 4425);
FORCEPROP 1 LAST PACK_TYPE 0402LF
J 0
(-7475 4375);
DISPLAY 0.489362 (-7475 4375);
PAINT SKYBLUE (-7475 4375);
FORCEPROP 2 LAST CDS_LIB pure_quanta
J 0
(-7725 4375);
DISPLAY INVISIBLE (-7725 4375);
FORCEPROP 1 LAST PATH I271
J 0
(-7775 4525);
DISPLAY 0.978723 (-7775 4525);
PAINT WHITE (-7775 4525);
DISPLAY INVISIBLE (-7775 4525);
FORCEADD Q_RES..1
(-7350 5225);
FORCEPROP 1 LAST LOCATION PR71
J 0
(-7600 5225);
DISPLAY 0.489362 (-7600 5225);
PAINT SKYBLUE (-7600 5225);
FORCEPROP 0 LAST $SEC 1
J 0
(-7400 5325);
DISPLAY 0.680851 (-7400 5325);
PAINT MONO (-7400 5325);
DISPLAY INVISIBLE (-7400 5325);
FORCEPROP 0 LAST CDS_SEC 1
J 0
(-7400 5325);
DISPLAY 1.021277 (-7400 5325);
DISPLAY INVISIBLE (-7400 5325);
FORCEPROP 1 LASTPIN (-7450 5225) $PN 1
J 0
(-7438 5237);
DISPLAY 0.489362 (-7438 5237);
PAINT MONO (-7438 5237);
FORCEPROP 1 LASTPIN (-7250 5225) $PN 2
J 0
(-7288 5237);
DISPLAY 0.489362 (-7288 5237);
PAINT MONO (-7288 5237);
FORCEPROP 1 LAST PART_NUMBER CS00002JB38
J 0
(-8025 5175);
DISPLAY 0.489362 (-8025 5175);
PAINT SKYBLUE (-8025 5175);
FORCEPROP 1 LAST MATERIAL CHIP
J 0
(-7675 5175);
DISPLAY 0.489362 (-7675 5175);
PAINT SKYBLUE (-7675 5175);
FORCEPROP 1 LAST TOLERANCE 5%
J 0
(-7325 5175);
DISPLAY 0.489362 (-7325 5175);
PAINT SKYBLUE (-7325 5175);
FORCEPROP 1 LAST PACK_TYPE 0402LF
J 0
(-7250 5175);
DISPLAY 0.489362 (-7250 5175);
PAINT SKYBLUE (-7250 5175);
FORCEPROP 1 LAST VALUE 0
J 2
(-7350 5175);
DISPLAY 0.489362 (-7350 5175);
PAINT SKYBLUE (-7350 5175);
FORCEPROP 1 LAST WATTAGE 1/16W
J 2
(-7425 5175);
DISPLAY 0.489362 (-7425 5175);
PAINT SKYBLUE (-7425 5175);
FORCEPROP 2 LAST CDS_LIB pure_quanta
J 0
(-7350 5225);
DISPLAY INVISIBLE (-7350 5225);
FORCEPROP 1 LAST PATH I273
J 0
(-7400 5375);
DISPLAY 0.978723 (-7400 5375);
PAINT WHITE (-7400 5375);
DISPLAY INVISIBLE (-7400 5375);
FORCEADD Q_CAP..2
(-7250 6100);
FORCEPROP 1 LAST LOCATION PC69
J 1
(-7425 6100);
DISPLAY 0.489362 (-7425 6100);
PAINT SKYBLUE (-7425 6100);
FORCEPROP 0 LAST $SEC 1
J 0
(-7300 6200);
DISPLAY 0.680851 (-7300 6200);
PAINT MONO (-7300 6200);
DISPLAY INVISIBLE (-7300 6200);
FORCEPROP 0 LAST CDS_SEC 1
J 0
(-7300 6200);
DISPLAY 1.021277 (-7300 6200);
DISPLAY INVISIBLE (-7300 6200);
FORCEPROP 1 LASTPIN (-7350 6100) $PN 1
J 0
(-7360 6115);
DISPLAY 0.489362 (-7360 6115);
PAINT MONO (-7360 6115);
FORCEPROP 1 LASTPIN (-7150 6100) $PN 2
J 0
(-7165 6115);
DISPLAY 0.489362 (-7165 6115);
PAINT MONO (-7165 6115);
FORCEPROP 1 LAST TOLERANCE 5%
J 2
(-6600 6050);
DISPLAY 0.489362 (-6600 6050);
PAINT SKYBLUE (-6600 6050);
FORCEPROP 1 LAST MATERIAL X7R
J 0
(-6775 6100);
DISPLAY 0.489362 (-6775 6100);
PAINT SKYBLUE (-6775 6100);
FORCEPROP 1 LAST VALUE 1000PF
J 2
(-6925 6100);
DISPLAY 0.489362 (-6925 6100);
PAINT SKYBLUE (-6925 6100);
FORCEPROP 1 LAST PART_NUMBER TMP_QCH21006JB10
J 1
(-6975 6050);
DISPLAY 0.489362 (-6975 6050);
PAINT SKYBLUE (-6975 6050);
FORCEPROP 1 LAST VOLTAGE 50V
J 0
(-6900 6100);
DISPLAY 0.489362 (-6900 6100);
PAINT SKYBLUE (-6900 6100);
FORCEPROP 1 LAST PACK_TYPE 0402
J 1
(-6750 6050);
DISPLAY 0.489362 (-6750 6050);
PAINT SKYBLUE (-6750 6050);
FORCEPROP 2 LAST CDS_LIB pure_quanta
J 0
(-7250 6100);
DISPLAY INVISIBLE (-7250 6100);
FORCEPROP 1 LAST PATH I274
J 0
(-7250 6300);
DISPLAY 0.978723 (-7250 6300);
PAINT WHITE (-7250 6300);
DISPLAY INVISIBLE (-7250 6300);
FORCEADD Q_RES..1
(-8075 6225);
FORCEPROP 1 LAST LOCATION PR58
J 0
(-8275 6225);
DISPLAY 0.489362 (-8275 6225);
PAINT SKYBLUE (-8275 6225);
FORCEPROP 0 LAST $SEC 1
J 0
(-8125 6325);
DISPLAY 0.680851 (-8125 6325);
PAINT MONO (-8125 6325);
DISPLAY INVISIBLE (-8125 6325);
FORCEPROP 0 LAST CDS_SEC 1
J 0
(-8125 6325);
DISPLAY 1.021277 (-8125 6325);
DISPLAY INVISIBLE (-8125 6325);
FORCEPROP 1 LASTPIN (-8175 6225) $PN 1
J 0
(-8163 6237);
DISPLAY 0.489362 (-8163 6237);
PAINT MONO (-8163 6237);
FORCEPROP 1 LASTPIN (-7975 6225) $PN 2
J 0
(-8013 6237);
DISPLAY 0.489362 (-8013 6237);
PAINT MONO (-8013 6237);
FORCEPROP 1 LAST WATTAGE 1/16W
J 2
(-7700 6325);
DISPLAY 0.489362 (-7700 6325);
PAINT SKYBLUE (-7700 6325);
FORCEPROP 1 LAST MATERIAL CHIP
J 0
(-7950 6325);
DISPLAY 0.489362 (-7950 6325);
PAINT SKYBLUE (-7950 6325);
FORCEPROP 1 LAST TOLERANCE 5%
J 0
(-7900 6225);
DISPLAY 0.489362 (-7900 6225);
PAINT SKYBLUE (-7900 6225);
FORCEPROP 1 LAST VALUE 0
J 2
(-7925 6225);
DISPLAY 0.489362 (-7925 6225);
PAINT SKYBLUE (-7925 6225);
FORCEPROP 1 LAST PART_NUMBER CS00002JB38
J 0
(-7950 6275);
DISPLAY 0.489362 (-7950 6275);
PAINT SKYBLUE (-7950 6275);
FORCEPROP 1 LAST PACK_TYPE 0402LF
J 0
(-7825 6225);
DISPLAY 0.489362 (-7825 6225);
PAINT SKYBLUE (-7825 6225);
FORCEPROP 2 LAST CDS_LIB pure_quanta
J 0
(-8075 6225);
DISPLAY INVISIBLE (-8075 6225);
FORCEPROP 1 LAST PATH I275
J 0
(-8125 6375);
DISPLAY 0.978723 (-8125 6375);
PAINT WHITE (-8125 6375);
DISPLAY INVISIBLE (-8125 6375);
FORCEADD VCC_CORE..1
(-8500 6625);
FORCEPROP 3 LASTPIN (-8500 6575) SIG_NAME P3V3_STBY\g
J 0
(-8490 6585);
DISPLAY 0.659574 (-8490 6585);
PAINT MONO (-8490 6585);
DISPLAY INVISIBLE (-8490 6585);
FORCEPROP 1 LAST HDL_POWER P3V3_STBY
J 1
(-8500 6675);
DISPLAY 0.489362 (-8500 6675);
PAINT GREEN (-8500 6675);
FORCEPROP 2 LAST CDS_LIB pure_quanta_power
J 0
(-8500 6625);
DISPLAY INVISIBLE (-8500 6625);
FORCEPROP 1 LAST PATH I276
J 0
(-8450 6650);
DISPLAY 0.872340 (-8450 6650);
PAINT AQUA (-8450 6650);
DISPLAY INVISIBLE (-8450 6650);
FORCEADD Q_RES..1
(-8075 6375);
FORCEPROP 1 LAST LOCATION PR57
J 0
(-8275 6375);
DISPLAY 0.489362 (-8275 6375);
PAINT SKYBLUE (-8275 6375);
FORCEPROP 0 LAST $SEC 1
J 0
(-8125 6475);
DISPLAY 0.680851 (-8125 6475);
PAINT MONO (-8125 6475);
DISPLAY INVISIBLE (-8125 6475);
FORCEPROP 0 LAST CDS_SEC 1
J 0
(-8125 6475);
DISPLAY 1.021277 (-8125 6475);
DISPLAY INVISIBLE (-8125 6475);
FORCEPROP 1 LASTPIN (-8175 6375) $PN 1
J 0
(-8163 6387);
DISPLAY 0.489362 (-8163 6387);
PAINT MONO (-8163 6387);
FORCEPROP 1 LASTPIN (-7975 6375) $PN 2
J 0
(-8013 6387);
DISPLAY 0.489362 (-8013 6387);
PAINT MONO (-8013 6387);
FORCEPROP 1 LAST WATTAGE 1/16W
J 2
(-7700 6475);
DISPLAY 0.489362 (-7700 6475);
PAINT SKYBLUE (-7700 6475);
FORCEPROP 1 LAST MATERIAL CHIP
J 0
(-7950 6475);
DISPLAY 0.489362 (-7950 6475);
PAINT SKYBLUE (-7950 6475);
FORCEPROP 1 LAST TOLERANCE 5%
J 0
(-7900 6375);
DISPLAY 0.489362 (-7900 6375);
PAINT SKYBLUE (-7900 6375);
FORCEPROP 1 LAST VALUE 0
J 2
(-7925 6375);
DISPLAY 0.489362 (-7925 6375);
PAINT SKYBLUE (-7925 6375);
FORCEPROP 1 LAST PART_NUMBER CS00002JB38
J 0
(-7950 6425);
DISPLAY 0.489362 (-7950 6425);
PAINT SKYBLUE (-7950 6425);
FORCEPROP 1 LAST PACK_TYPE 0402LF
J 0
(-7825 6375);
DISPLAY 0.489362 (-7825 6375);
PAINT SKYBLUE (-7825 6375);
FORCEPROP 2 LAST CDS_LIB pure_quanta
J 0
(-8075 6375);
DISPLAY INVISIBLE (-8075 6375);
FORCEPROP 1 LAST PATH I277
J 0
(-8125 6525);
DISPLAY 0.978723 (-8125 6525);
PAINT WHITE (-8125 6525);
DISPLAY INVISIBLE (-8125 6525);
FORCEADD Q_RES..1
(-8075 6525);
FORCEPROP 1 LAST LOCATION PR56
J 0
(-8275 6525);
DISPLAY 0.489362 (-8275 6525);
PAINT SKYBLUE (-8275 6525);
FORCEPROP 0 LAST $SEC 1
J 0
(-8125 6625);
DISPLAY 0.680851 (-8125 6625);
PAINT MONO (-8125 6625);
DISPLAY INVISIBLE (-8125 6625);
FORCEPROP 0 LAST CDS_SEC 1
J 0
(-8125 6625);
DISPLAY 1.021277 (-8125 6625);
DISPLAY INVISIBLE (-8125 6625);
FORCEPROP 1 LASTPIN (-8175 6525) $PN 1
J 0
(-8163 6537);
DISPLAY 0.489362 (-8163 6537);
PAINT MONO (-8163 6537);
FORCEPROP 1 LASTPIN (-7975 6525) $PN 2
J 0
(-8013 6537);
DISPLAY 0.489362 (-8013 6537);
PAINT MONO (-8013 6537);
FORCEPROP 1 LAST WATTAGE 1/16W
J 2
(-7700 6625);
DISPLAY 0.489362 (-7700 6625);
PAINT SKYBLUE (-7700 6625);
FORCEPROP 1 LAST MATERIAL CHIP
J 0
(-7950 6625);
DISPLAY 0.489362 (-7950 6625);
PAINT SKYBLUE (-7950 6625);
FORCEPROP 1 LAST TOLERANCE 1%
J 0
(-7875 6525);
DISPLAY 0.489362 (-7875 6525);
PAINT SKYBLUE (-7875 6525);
FORCEPROP 1 LAST VALUE 1K
J 2
(-7900 6525);
DISPLAY 0.489362 (-7900 6525);
PAINT SKYBLUE (-7900 6525);
FORCEPROP 1 LAST PART_NUMBER TMP_QCS21002FB24
J 0
(-7950 6575);
DISPLAY 0.489362 (-7950 6575);
PAINT SKYBLUE (-7950 6575);
FORCEPROP 1 LAST PACK_TYPE 0402LF
J 0
(-7775 6525);
DISPLAY 0.489362 (-7775 6525);
PAINT SKYBLUE (-7775 6525);
FORCEPROP 2 LAST CDS_LIB pure_quanta
J 0
(-8075 6525);
DISPLAY INVISIBLE (-8075 6525);
FORCEPROP 1 LAST PATH I278
J 0
(-8125 6675);
DISPLAY 0.978723 (-8125 6675);
PAINT WHITE (-8125 6675);
DISPLAY INVISIBLE (-8125 6675);
FORCEADD Q_CAP..2
(-7225 6525);
FORCEPROP 1 LAST LOCATION PC70
J 1
(-7425 6525);
DISPLAY 0.489362 (-7425 6525);
PAINT SKYBLUE (-7425 6525);
FORCEPROP 0 LAST $SEC 1
J 0
(-7275 6625);
DISPLAY 0.680851 (-7275 6625);
PAINT MONO (-7275 6625);
DISPLAY INVISIBLE (-7275 6625);
FORCEPROP 0 LAST CDS_SEC 1
J 0
(-7275 6625);
DISPLAY 1.021277 (-7275 6625);
DISPLAY INVISIBLE (-7275 6625);
FORCEPROP 1 LASTPIN (-7325 6525) $PN 1
J 0
(-7335 6540);
DISPLAY 0.489362 (-7335 6540);
PAINT MONO (-7335 6540);
FORCEPROP 1 LASTPIN (-7125 6525) $PN 2
J 0
(-7140 6540);
DISPLAY 0.489362 (-7140 6540);
PAINT MONO (-7140 6540);
FORCEPROP 1 LAST PART_NUMBER TMP_QCH21006JB10
J 1
(-6950 6475);
DISPLAY 0.489362 (-6950 6475);
PAINT SKYBLUE (-6950 6475);
FORCEPROP 1 LAST MATERIAL EMPTY
J 0
(-6750 6525);
DISPLAY 0.489362 (-6750 6525);
PAINT RED (-6750 6525);
FORCEPROP 1 LAST TOLERANCE 5%
J 2
(-6575 6475);
DISPLAY 0.489362 (-6575 6475);
PAINT SKYBLUE (-6575 6475);
FORCEPROP 1 LAST VALUE 1000PF
J 2
(-6900 6525);
DISPLAY 0.489362 (-6900 6525);
PAINT SKYBLUE (-6900 6525);
FORCEPROP 1 LAST VOLTAGE 50V
J 0
(-6875 6525);
DISPLAY 0.489362 (-6875 6525);
PAINT SKYBLUE (-6875 6525);
FORCEPROP 1 LAST PACK_TYPE 0402
J 1
(-6725 6475);
DISPLAY 0.489362 (-6725 6475);
PAINT SKYBLUE (-6725 6475);
FORCEPROP 2 LAST CDS_LIB pure_quanta
J 0
(-7225 6525);
DISPLAY INVISIBLE (-7225 6525);
FORCEPROP 1 LAST PATH I279
J 0
(-7225 6725);
DISPLAY 0.978723 (-7225 6725);
PAINT WHITE (-7225 6725);
DISPLAY INVISIBLE (-7225 6725);
FORCEADD UNIVERSAL_GND..1
(-6675 450);
FORCEPROP 3 LASTPIN (-6675 500) SIG_NAME GND\g
J 0
(-6665 510);
DISPLAY 0.659574 (-6665 510);
PAINT MONO (-6665 510);
DISPLAY INVISIBLE (-6665 510);
FORCEPROP 2 LAST CDS_LIB pure_quanta_power
J 0
(-6675 450);
PAINT MONO (-6675 450);
DISPLAY INVISIBLE (-6675 450);
FORCEPROP 1 LAST PATH I280
J 0
(-6600 450);
DISPLAY 0.872340 (-6600 450);
PAINT AQUA (-6600 450);
DISPLAY INVISIBLE (-6600 450);
FORCEPROP 1 LAST HDL_POWER GND
J 1
(-6650 375);
DISPLAY 0.872340 (-6650 375);
PAINT GREEN (-6650 375);
DISPLAY INVISIBLE (-6650 375);
FORCEADD Q_CAP..1
(-6675 650);
FORCEPROP 1 LAST LOCATION PC74
J 0
(-6625 775);
DISPLAY 0.489362 (-6625 775);
PAINT SKYBLUE (-6625 775);
FORCEPROP 0 LAST $SEC 1
J 0
(-6625 825);
DISPLAY 0.680851 (-6625 825);
PAINT MONO (-6625 825);
DISPLAY INVISIBLE (-6625 825);
FORCEPROP 0 LAST CDS_SEC 1
J 0
(-6625 825);
DISPLAY 1.021277 (-6625 825);
DISPLAY INVISIBLE (-6625 825);
FORCEPROP 1 LASTPIN (-6675 750) $PN 1
J 0
(-6665 730);
DISPLAY 0.489362 (-6665 730);
PAINT MONO (-6665 730);
FORCEPROP 1 LASTPIN (-6675 550) $PN 2
J 0
(-6665 530);
DISPLAY 0.489362 (-6665 530);
PAINT MONO (-6665 530);
FORCEPROP 1 LAST PART_NUMBER CH4104K1B00
J 0
(-6625 475);
DISPLAY 0.489362 (-6625 475);
PAINT SKYBLUE (-6625 475);
FORCEPROP 1 LAST VALUE 0.1UF
J 0
(-6625 725);
DISPLAY 0.489362 (-6625 725);
PAINT SKYBLUE (-6625 725);
FORCEPROP 1 LAST VOLTAGE 25V
J 0
(-6625 675);
DISPLAY 0.489362 (-6625 675);
PAINT SKYBLUE (-6625 675);
FORCEPROP 1 LAST PACK_TYPE 0402
J 0
(-6625 525);
DISPLAY 0.489362 (-6625 525);
PAINT SKYBLUE (-6625 525);
FORCEPROP 1 LAST MATERIAL X7R
J 0
(-6625 575);
DISPLAY 0.489362 (-6625 575);
PAINT SKYBLUE (-6625 575);
FORCEPROP 1 LAST TOLERANCE 10%
J 0
(-6625 625);
DISPLAY 0.489362 (-6625 625);
PAINT SKYBLUE (-6625 625);
FORCEPROP 2 LAST CDS_LIB pure_quanta
J 0
(-6675 650);
DISPLAY INVISIBLE (-6675 650);
FORCEPROP 1 LAST PATH I281
J 0
(-6625 800);
DISPLAY 0.978723 (-6625 800);
PAINT WHITE (-6625 800);
DISPLAY INVISIBLE (-6625 800);
FORCEADD UNIVERSAL_GND..1
(-6450 700);
FORCEPROP 3 LASTPIN (-6450 750) SIG_NAME GND\g
J 0
(-6440 760);
DISPLAY 0.659574 (-6440 760);
PAINT MONO (-6440 760);
DISPLAY INVISIBLE (-6440 760);
FORCEPROP 2 LAST CDS_LIB pure_quanta_power
J 0
(-6450 700);
PAINT MONO (-6450 700);
DISPLAY INVISIBLE (-6450 700);
FORCEPROP 1 LAST PATH I282
J 0
(-6375 700);
DISPLAY 0.872340 (-6375 700);
PAINT AQUA (-6375 700);
DISPLAY INVISIBLE (-6375 700);
FORCEPROP 1 LAST HDL_POWER GND
J 1
(-6425 625);
DISPLAY 0.872340 (-6425 625);
PAINT GREEN (-6425 625);
DISPLAY INVISIBLE (-6425 625);
FORCEADD UNIVERSAL_GND..1
R 1
(-6475 1275);
FORCEPROP 3 LASTPIN (-6525 1275) SIG_NAME GND\g
J 0
(-6515 1285);
DISPLAY 0.659574 (-6515 1285);
PAINT MONO (-6515 1285);
DISPLAY INVISIBLE (-6515 1285);
FORCEPROP 2 LAST CDS_LIB pure_quanta_power
J 0
(-6475 1275);
PAINT MONO (-6475 1275);
DISPLAY INVISIBLE (-6475 1275);
FORCEPROP 1 LAST PATH I284
R 1
J 0
(-6475 1350);
DISPLAY 0.872340 (-6475 1350);
PAINT AQUA (-6475 1350);
DISPLAY INVISIBLE (-6475 1350);
FORCEPROP 1 LAST HDL_POWER GND
R 1
J 1
(-6400 1300);
DISPLAY 0.872340 (-6400 1300);
PAINT GREEN (-6400 1300);
DISPLAY INVISIBLE (-6400 1300);
FORCEADD UNIVERSAL_GND..1
(-4350 750);
FORCEPROP 3 LASTPIN (-4350 800) SIG_NAME GND\g
J 0
(-4340 810);
DISPLAY 0.659574 (-4340 810);
PAINT MONO (-4340 810);
DISPLAY INVISIBLE (-4340 810);
FORCEPROP 2 LAST CDS_LIB pure_quanta_power
J 0
(-4350 750);
PAINT MONO (-4350 750);
DISPLAY INVISIBLE (-4350 750);
FORCEPROP 1 LAST PATH I285
J 0
(-4275 750);
DISPLAY 0.872340 (-4275 750);
PAINT AQUA (-4275 750);
DISPLAY INVISIBLE (-4275 750);
FORCEPROP 1 LAST HDL_POWER GND
J 1
(-4325 675);
DISPLAY 0.872340 (-4325 675);
PAINT GREEN (-4325 675);
DISPLAY INVISIBLE (-4325 675);
FORCEADD Q_CAP..1
(-4350 1000);
FORCEPROP 1 LAST LOCATION PC78
J 0
(-4300 1100);
DISPLAY 0.489362 (-4300 1100);
PAINT SKYBLUE (-4300 1100);
FORCEPROP 0 LAST $SEC 1
J 0
(-4300 1150);
DISPLAY 0.680851 (-4300 1150);
PAINT MONO (-4300 1150);
DISPLAY INVISIBLE (-4300 1150);
FORCEPROP 0 LAST CDS_SEC 1
J 0
(-4300 1150);
DISPLAY 1.021277 (-4300 1150);
DISPLAY INVISIBLE (-4300 1150);
FORCEPROP 1 LASTPIN (-4350 1100) $PN 1
J 0
(-4340 1080);
DISPLAY 0.489362 (-4340 1080);
PAINT MONO (-4340 1080);
FORCEPROP 1 LASTPIN (-4350 900) $PN 2
J 0
(-4340 880);
DISPLAY 0.489362 (-4340 880);
PAINT MONO (-4340 880);
FORCEPROP 1 LAST PACK_TYPE 0402
J 0
(-4300 850);
DISPLAY 0.489362 (-4300 850);
PAINT SKYBLUE (-4300 850);
FORCEPROP 1 LAST TOLERANCE 10%
J 0
(-4300 950);
DISPLAY 0.489362 (-4300 950);
PAINT SKYBLUE (-4300 950);
FORCEPROP 1 LAST MATERIAL X7R
J 0
(-4300 900);
DISPLAY 0.489362 (-4300 900);
PAINT SKYBLUE (-4300 900);
FORCEPROP 1 LAST VALUE 470PF
J 0
(-4300 1050);
DISPLAY 0.489362 (-4300 1050);
PAINT SKYBLUE (-4300 1050);
FORCEPROP 1 LAST PART_NUMBER TMP_QCH14706KB18
J 0
(-4300 775);
DISPLAY 0.489362 (-4300 775);
PAINT SKYBLUE (-4300 775);
FORCEPROP 1 LAST VOLTAGE 50V
J 0
(-4300 1000);
DISPLAY 0.489362 (-4300 1000);
PAINT SKYBLUE (-4300 1000);
FORCEPROP 2 LAST CDS_LIB pure_quanta
J 0
(-4350 1000);
DISPLAY INVISIBLE (-4350 1000);
FORCEPROP 1 LAST PATH I286
J 0
(-4300 1150);
DISPLAY 0.978723 (-4300 1150);
PAINT WHITE (-4300 1150);
DISPLAY INVISIBLE (-4300 1150);
FORCEADD OFFPAGE..4
(-3750 1175);
FORCEPROP 2 LAST $XR2 179 
J 0
(-3324 1175);
DISPLAY 0.638298 (-3324 1175);
PAINT MONO (-3324 1175);
FORCEPROP 2 LAST $XR1 178 
J 0
(-3444 1175);
DISPLAY 0.638298 (-3444 1175);
PAINT MONO (-3444 1175);
FORCEPROP 2 LAST $XR0 177 
J 0
(-3564 1175);
DISPLAY 0.638298 (-3564 1175);
PAINT MONO (-3564 1175);
FORCEPROP 2 LAST PATH I291
J 0
(-2950 1225);
DISPLAY 1.021277 (-2950 1225);
DISPLAY INVISIBLE (-2950 1225);
FORCEPROP 1 LAST COMMENT_BODY TRUE
J 0
(-3775 1075);
DISPLAY 0.872340 (-3775 1075);
PAINT GREEN (-3775 1075);
DISPLAY INVISIBLE (-3775 1075);
FORCEPROP 1 LAST OFFPAGE TRUE
J 0
(-3425 1050);
DISPLAY 0.872340 (-3425 1050);
PAINT GREEN (-3425 1050);
DISPLAY INVISIBLE (-3425 1050);
FORCEPROP 2 LAST CDS_LIB standard
J 0
(-3750 1175);
DISPLAY INVISIBLE (-3750 1175);
FORCEADD UNIVERSAL_GND..1
R 1
(-6525 6100);
FORCEPROP 3 LASTPIN (-6575 6100) SIG_NAME GND\g
J 0
(-6565 6110);
DISPLAY 0.659574 (-6565 6110);
PAINT MONO (-6565 6110);
DISPLAY INVISIBLE (-6565 6110);
FORCEPROP 2 LAST CDS_LIB pure_quanta_power
J 0
(-6525 6100);
PAINT MONO (-6525 6100);
DISPLAY INVISIBLE (-6525 6100);
FORCEPROP 1 LAST PATH I311
R 1
J 0
(-6525 6175);
DISPLAY 0.872340 (-6525 6175);
PAINT AQUA (-6525 6175);
DISPLAY INVISIBLE (-6525 6175);
FORCEPROP 1 LAST HDL_POWER GND
R 1
J 1
(-6450 6125);
DISPLAY 0.872340 (-6450 6125);
PAINT GREEN (-6450 6125);
DISPLAY INVISIBLE (-6450 6125);
FORCEADD UNIVERSAL_GND..1
R 1
(-6525 6525);
FORCEPROP 3 LASTPIN (-6575 6525) SIG_NAME GND\g
J 0
(-6565 6535);
DISPLAY 0.659574 (-6565 6535);
PAINT MONO (-6565 6535);
DISPLAY INVISIBLE (-6565 6535);
FORCEPROP 2 LAST CDS_LIB pure_quanta_power
J 0
(-6525 6525);
PAINT MONO (-6525 6525);
DISPLAY INVISIBLE (-6525 6525);
FORCEPROP 1 LAST PATH I312
R 1
J 0
(-6525 6600);
DISPLAY 0.872340 (-6525 6600);
PAINT AQUA (-6525 6600);
DISPLAY INVISIBLE (-6525 6600);
FORCEPROP 1 LAST HDL_POWER GND
R 1
J 1
(-6450 6550);
DISPLAY 0.872340 (-6450 6550);
PAINT GREEN (-6450 6550);
DISPLAY INVISIBLE (-6450 6550);
FORCEADD Q_CAP..1
(-4350 5725);
FORCEPROP 1 LAST LOCATION PC76
J 0
(-4300 5850);
DISPLAY 0.489362 (-4300 5850);
PAINT SKYBLUE (-4300 5850);
FORCEPROP 2 LAST $SEC 1
J 0
(-4300 5925);
DISPLAY 0.680851 (-4300 5925);
PAINT MONO (-4300 5925);
DISPLAY INVISIBLE (-4300 5925);
FORCEPROP 2 LAST CDS_SEC 1
J 0
(-4300 5925);
DISPLAY 1.021277 (-4300 5925);
DISPLAY INVISIBLE (-4300 5925);
FORCEPROP 1 LASTPIN (-4350 5825) $PN 1
J 0
(-4340 5805);
DISPLAY 0.489362 (-4340 5805);
FORCEPROP 1 LASTPIN (-4350 5625) $PN 2
J 0
(-4340 5605);
DISPLAY 0.489362 (-4340 5605);
FORCEPROP 1 LAST PART_NUMBER CH6101MEB01
J 0
(-4300 5550);
DISPLAY 0.489362 (-4300 5550);
PAINT SKYBLUE (-4300 5550);
FORCEPROP 1 LAST PACK_TYPE C0402
J 0
(-4300 5600);
DISPLAY 0.489362 (-4300 5600);
PAINT SKYBLUE (-4300 5600);
FORCEPROP 1 LAST VOLTAGE 6.3V
J 0
(-4300 5750);
DISPLAY 0.489362 (-4300 5750);
PAINT SKYBLUE (-4300 5750);
FORCEPROP 1 LAST MATERIAL X6S
J 0
(-4300 5650);
DISPLAY 0.489362 (-4300 5650);
PAINT SKYBLUE (-4300 5650);
FORCEPROP 1 LAST TOLERANCE 20%
J 0
(-4300 5700);
DISPLAY 0.489362 (-4300 5700);
PAINT SKYBLUE (-4300 5700);
FORCEPROP 1 LAST VALUE 10UF
J 0
(-4300 5800);
DISPLAY 0.489362 (-4300 5800);
PAINT SKYBLUE (-4300 5800);
FORCEPROP 2 LAST CDS_LIB pure_quanta
J 0
(-4350 5725);
PAINT MONO (-4350 5725);
DISPLAY INVISIBLE (-4350 5725);
FORCEPROP 1 LAST PATH I319
J 0
(-4300 5875);
DISPLAY 0.978723 (-4300 5875);
PAINT WHITE (-4300 5875);
DISPLAY INVISIBLE (-4300 5875);
FORCEADD Q_CAP..1
(-4350 6200);
FORCEPROP 1 LAST LOCATION PC75
J 0
(-4300 6325);
DISPLAY 0.489362 (-4300 6325);
PAINT SKYBLUE (-4300 6325);
FORCEPROP 0 LAST $SEC 1
J 0
(-4300 6375);
DISPLAY 0.680851 (-4300 6375);
PAINT MONO (-4300 6375);
DISPLAY INVISIBLE (-4300 6375);
FORCEPROP 0 LAST CDS_SEC 1
J 0
(-4300 6375);
DISPLAY 1.021277 (-4300 6375);
DISPLAY INVISIBLE (-4300 6375);
FORCEPROP 1 LASTPIN (-4350 6300) $PN 1
J 0
(-4340 6280);
DISPLAY 0.489362 (-4340 6280);
PAINT MONO (-4340 6280);
FORCEPROP 1 LASTPIN (-4350 6100) $PN 2
J 0
(-4340 6080);
DISPLAY 0.489362 (-4340 6080);
PAINT MONO (-4340 6080);
FORCEPROP 1 LAST MATERIAL X6S
J 0
(-4300 6125);
DISPLAY 0.489362 (-4300 6125);
PAINT SKYBLUE (-4300 6125);
FORCEPROP 1 LAST TOLERANCE 10%
J 0
(-4300 6175);
DISPLAY 0.489362 (-4300 6175);
PAINT SKYBLUE (-4300 6175);
FORCEPROP 1 LAST VALUE 1UF
J 0
(-4300 6275);
DISPLAY 0.489362 (-4300 6275);
PAINT SKYBLUE (-4300 6275);
FORCEPROP 1 LAST PART_NUMBER CH5103KEB01
J 0
(-4300 6025);
DISPLAY 0.489362 (-4300 6025);
PAINT SKYBLUE (-4300 6025);
FORCEPROP 1 LAST VOLTAGE 16V
J 0
(-4300 6225);
DISPLAY 0.489362 (-4300 6225);
PAINT SKYBLUE (-4300 6225);
FORCEPROP 1 LAST PACK_TYPE C0402
J 0
(-4300 6075);
DISPLAY 0.489362 (-4300 6075);
PAINT SKYBLUE (-4300 6075);
FORCEPROP 2 LAST CDS_LIB pure_quanta
J 0
(-4350 6200);
DISPLAY INVISIBLE (-4350 6200);
FORCEPROP 1 LAST PATH I322
J 0
(-4300 6350);
DISPLAY 0.978723 (-4300 6350);
PAINT WHITE (-4300 6350);
DISPLAY INVISIBLE (-4300 6350);
FORCEADD Q_RES..1
(-3900 6375);
FORCEPROP 1 LAST LOCATION PR76
J 0
(-4125 6375);
DISPLAY 0.489362 (-4125 6375);
PAINT SKYBLUE (-4125 6375);
FORCEPROP 0 LAST $SEC 1
J 0
(-3950 6475);
DISPLAY 0.680851 (-3950 6475);
PAINT MONO (-3950 6475);
DISPLAY INVISIBLE (-3950 6475);
FORCEPROP 0 LAST CDS_SEC 1
J 0
(-3950 6475);
DISPLAY 1.021277 (-3950 6475);
DISPLAY INVISIBLE (-3950 6475);
FORCEPROP 1 LASTPIN (-4000 6375) $PN 1
J 0
(-3988 6387);
DISPLAY 0.489362 (-3988 6387);
PAINT MONO (-3988 6387);
FORCEPROP 1 LASTPIN (-3800 6375) $PN 2
J 0
(-3838 6387);
DISPLAY 0.489362 (-3838 6387);
PAINT MONO (-3838 6387);
FORCEPROP 1 LAST WATTAGE 1/16W
J 2
(-3450 6275);
DISPLAY 0.489362 (-3450 6275);
PAINT SKYBLUE (-3450 6275);
FORCEPROP 1 LAST MATERIAL CHIP
J 0
(-3600 6400);
DISPLAY 0.489362 (-3600 6400);
PAINT SKYBLUE (-3600 6400);
FORCEPROP 1 LAST TOLERANCE 1%
J 0
(-3700 6400);
DISPLAY 0.489362 (-3700 6400);
PAINT SKYBLUE (-3700 6400);
FORCEPROP 1 LAST VALUE 1
J 2
(-3725 6400);
DISPLAY 0.489362 (-3725 6400);
PAINT SKYBLUE (-3725 6400);
FORCEPROP 1 LAST PART_NUMBER CS-1002FB23
J 0
(-3750 6325);
DISPLAY 0.489362 (-3750 6325);
PAINT SKYBLUE (-3750 6325);
FORCEPROP 1 LAST PACK_TYPE 0402LF
J 0
(-3750 6275);
DISPLAY 0.489362 (-3750 6275);
PAINT SKYBLUE (-3750 6275);
FORCEPROP 2 LAST CDS_LIB pure_quanta
J 0
(-3900 6375);
DISPLAY INVISIBLE (-3900 6375);
FORCEPROP 1 LAST PATH I325
J 0
(-3950 6525);
DISPLAY 0.978723 (-3950 6525);
PAINT WHITE (-3950 6525);
DISPLAY INVISIBLE (-3950 6525);
FORCEADD VCC_CORE..1
(-3375 6500);
FORCEPROP 3 LASTPIN (-3375 6450) SIG_NAME P3V3_STBY\g
J 0
(-3365 6460);
DISPLAY 0.659574 (-3365 6460);
PAINT MONO (-3365 6460);
DISPLAY INVISIBLE (-3365 6460);
FORCEPROP 1 LAST HDL_POWER P3V3_STBY
J 1
(-3375 6550);
DISPLAY 0.489362 (-3375 6550);
PAINT GREEN (-3375 6550);
FORCEPROP 2 LAST CDS_LIB pure_quanta_power
J 0
(-3375 6500);
DISPLAY INVISIBLE (-3375 6500);
FORCEPROP 1 LAST PATH I326
J 0
(-3325 6525);
DISPLAY 0.872340 (-3325 6525);
PAINT AQUA (-3325 6525);
DISPLAY INVISIBLE (-3325 6525);
FORCEADD OFFPAGE..1
(-9950 4000);
FORCEPROP 2 LAST $XR1 183 
J 0
(-10351 4000);
DISPLAY 0.638298 (-10351 4000);
PAINT MONO (-10351 4000);
FORCEPROP 2 LAST $XR0 27 
J 0
(-10231 4000);
DISPLAY 0.638298 (-10231 4000);
PAINT MONO (-10231 4000);
FORCEPROP 2 LAST PATH I336
J 0
(-10225 4050);
DISPLAY 1.021277 (-10225 4050);
DISPLAY INVISIBLE (-10225 4050);
FORCEPROP 1 LAST COMMENT_BODY TRUE
J 0
(-9825 3900);
DISPLAY 0.872340 (-9825 3900);
PAINT GREEN (-9825 3900);
DISPLAY INVISIBLE (-9825 3900);
FORCEPROP 1 LAST OFFPAGE TRUE
J 0
(-9625 3875);
DISPLAY 0.872340 (-9625 3875);
PAINT GREEN (-9625 3875);
DISPLAY INVISIBLE (-9625 3875);
FORCEPROP 2 LAST CDS_LIB standard
J 0
(-9950 4000);
DISPLAY INVISIBLE (-9950 4000);
FORCEADD RAA229620GNPHA0..1
(-5700 3625);
FORCEPROP 1 LAST LOCATION PU12
J 0
(-6250 6650);
DISPLAY 0.489362 (-6250 6650);
PAINT SKYBLUE (-6250 6650);
FORCEPROP 0 LAST $SEC 1
J 0
(-6250 6675);
DISPLAY 0.680851 (-6250 6675);
PAINT MONO (-6250 6675);
DISPLAY INVISIBLE (-6250 6675);
FORCEPROP 0 LAST CDS_SEC 1
J 0
(-6250 6675);
DISPLAY 1.021277 (-6250 6675);
DISPLAY INVISIBLE (-6250 6675);
FORCEPROP 0 LASTPIN (-5050 1975) $PN 38
J 0
(-5040 1985);
DISPLAY 0.489362 (-5040 1985);
PAINT MONO (-5040 1985);
FORCEPROP 0 LASTPIN (-5050 2275) $PN 37
J 0
(-5040 2285);
DISPLAY 0.489362 (-5040 2285);
PAINT MONO (-5040 2285);
FORCEPROP 0 LASTPIN (-5050 2575) $PN 36
J 0
(-5040 2585);
DISPLAY 0.489362 (-5040 2585);
PAINT MONO (-5040 2585);
FORCEPROP 0 LASTPIN (-5050 2875) $PN 35
J 0
(-5040 2885);
DISPLAY 0.489362 (-5040 2885);
PAINT MONO (-5040 2885);
FORCEPROP 0 LASTPIN (-5050 3175) $PN 34
J 0
(-5040 3185);
DISPLAY 0.489362 (-5040 3185);
PAINT MONO (-5040 3185);
FORCEPROP 0 LASTPIN (-5050 3475) $PN 33
J 0
(-5040 3485);
DISPLAY 0.489362 (-5040 3485);
PAINT MONO (-5040 3485);
FORCEPROP 0 LASTPIN (-5050 3775) $PN 32
J 0
(-5040 3785);
DISPLAY 0.489362 (-5040 3785);
PAINT MONO (-5040 3785);
FORCEPROP 0 LASTPIN (-5050 4075) $PN 31
J 0
(-5040 4085);
DISPLAY 0.489362 (-5040 4085);
PAINT MONO (-5040 4085);
FORCEPROP 0 LASTPIN (-5050 4375) $PN 30
J 0
(-5040 4385);
DISPLAY 0.489362 (-5040 4385);
PAINT MONO (-5040 4385);
FORCEPROP 0 LASTPIN (-5050 4675) $PN 29
J 0
(-5040 4685);
DISPLAY 0.489362 (-5040 4685);
PAINT MONO (-5040 4685);
FORCEPROP 0 LASTPIN (-5050 4975) $PN 28
J 0
(-5040 4985);
DISPLAY 0.489362 (-5040 4985);
PAINT MONO (-5040 4985);
FORCEPROP 0 LASTPIN (-5050 5275) $PN 27
J 0
(-5040 5285);
DISPLAY 0.489362 (-5040 5285);
PAINT MONO (-5040 5285);
FORCEPROP 0 LASTPIN (-6400 6225) $PN 17
J 2
(-6410 6235);
DISPLAY 0.489362 (-6410 6235);
PAINT MONO (-6410 6235);
FORCEPROP 0 LASTPIN (-6400 1625) $PN 42
J 2
(-6410 1635);
DISPLAY 0.489362 (-6410 1635);
PAINT MONO (-6410 1635);
FORCEPROP 0 LASTPIN (-6400 4925) $PN 15
J 2
(-6410 4935);
DISPLAY 0.489362 (-6410 4935);
PAINT MONO (-6410 4935);
FORCEPROP 0 LASTPIN (-6400 2375) $PN 41
J 2
(-6410 2385);
DISPLAY 0.489362 (-6410 2385);
PAINT MONO (-6410 2385);
FORCEPROP 0 LASTPIN (-6400 6375) $PN 16
J 2
(-6410 6385);
DISPLAY 0.489362 (-6410 6385);
PAINT MONO (-6410 6385);
FORCEPROP 0 LASTPIN (-6400 1125) $PN 20
J 2
(-6410 1135);
DISPLAY 0.489362 (-6410 1135);
PAINT MONO (-6410 1135);
FORCEPROP 0 LASTPIN (-6400 5225) $PN 14
J 2
(-6410 5235);
DISPLAY 0.489362 (-6410 5235);
PAINT MONO (-6410 5235);
FORCEPROP 0 LASTPIN (-6400 5075) $PN 13
J 2
(-6410 5085);
DISPLAY 0.489362 (-6410 5085);
PAINT MONO (-6410 5085);
FORCEPROP 0 LASTPIN (-5050 2075) $PN 1
J 0
(-5040 2085);
DISPLAY 0.489362 (-5040 2085);
PAINT MONO (-5040 2085);
FORCEPROP 0 LASTPIN (-5050 2375) $PN 2
J 0
(-5040 2385);
DISPLAY 0.489362 (-5040 2385);
PAINT MONO (-5040 2385);
FORCEPROP 0 LASTPIN (-5050 2675) $PN 3
J 0
(-5040 2685);
DISPLAY 0.489362 (-5040 2685);
PAINT MONO (-5040 2685);
FORCEPROP 0 LASTPIN (-5050 2975) $PN 4
J 0
(-5040 2985);
DISPLAY 0.489362 (-5040 2985);
PAINT MONO (-5040 2985);
FORCEPROP 0 LASTPIN (-5050 3275) $PN 5
J 0
(-5040 3285);
DISPLAY 0.489362 (-5040 3285);
PAINT MONO (-5040 3285);
FORCEPROP 0 LASTPIN (-5050 3575) $PN 6
J 0
(-5040 3585);
DISPLAY 0.489362 (-5040 3585);
PAINT MONO (-5040 3585);
FORCEPROP 0 LASTPIN (-5050 3875) $PN 7
J 0
(-5040 3885);
DISPLAY 0.489362 (-5040 3885);
PAINT MONO (-5040 3885);
FORCEPROP 0 LASTPIN (-5050 4175) $PN 8
J 0
(-5040 4185);
DISPLAY 0.489362 (-5040 4185);
PAINT MONO (-5040 4185);
FORCEPROP 0 LASTPIN (-5050 4475) $PN 9
J 0
(-5040 4485);
DISPLAY 0.489362 (-5040 4485);
PAINT MONO (-5040 4485);
FORCEPROP 0 LASTPIN (-5050 4775) $PN 10
J 0
(-5040 4785);
DISPLAY 0.489362 (-5040 4785);
PAINT MONO (-5040 4785);
FORCEPROP 0 LASTPIN (-5050 5075) $PN 11
J 0
(-5040 5085);
DISPLAY 0.489362 (-5040 5085);
PAINT MONO (-5040 5085);
FORCEPROP 0 LASTPIN (-5050 5375) $PN 12
J 0
(-5040 5385);
DISPLAY 0.489362 (-5040 5385);
PAINT MONO (-5040 5385);
FORCEPROP 0 LASTPIN (-6400 2525) $PN 18
J 2
(-6410 2535);
DISPLAY 0.489362 (-6410 2535);
PAINT MONO (-6410 2535);
FORCEPROP 0 LASTPIN (-6400 4075) $PN 26
J 2
(-6410 4085);
DISPLAY 0.489362 (-6410 4085);
PAINT MONO (-6410 4085);
FORCEPROP 0 LASTPIN (-6400 2975) $PN 39
J 2
(-6410 2985);
DISPLAY 0.489362 (-6410 2985);
PAINT MONO (-6410 2985);
FORCEPROP 0 LASTPIN (-6400 5925) $PN 22
J 2
(-6410 5935);
DISPLAY 0.489362 (-6410 5935);
PAINT MONO (-6410 5935);
FORCEPROP 0 LASTPIN (-6400 5775) $PN 21
J 2
(-6410 5785);
DISPLAY 0.489362 (-6410 5785);
PAINT MONO (-6410 5785);
FORCEPROP 0 LASTPIN (-6400 5475) $PN 24
J 2
(-6410 5485);
DISPLAY 0.489362 (-6410 5485);
PAINT MONO (-6410 5485);
FORCEPROP 0 LASTPIN (-6400 5625) $PN 23
J 2
(-6410 5635);
DISPLAY 0.489362 (-6410 5635);
PAINT MONO (-6410 5635);
FORCEPROP 0 LASTPIN (-5050 1175) $PN 44
J 0
(-5040 1185);
DISPLAY 0.489362 (-5040 1185);
PAINT MONO (-5040 1185);
FORCEPROP 0 LASTPIN (-5050 1475) $PN 43
J 0
(-5040 1485);
DISPLAY 0.489362 (-5040 1485);
PAINT MONO (-5040 1485);
FORCEPROP 0 LASTPIN (-6400 825) $PN TH
J 2
(-6410 835);
DISPLAY 0.489362 (-6410 835);
PAINT MONO (-6410 835);
FORCEPROP 0 LASTPIN (-5050 6375) $PN 47
J 0
(-5040 6385);
DISPLAY 0.489362 (-5040 6385);
PAINT MONO (-5040 6385);
FORCEPROP 0 LASTPIN (-5050 6075) $PN 48
J 0
(-5040 6085);
DISPLAY 0.489362 (-5040 6085);
PAINT MONO (-5040 6085);
FORCEPROP 0 LASTPIN (-6400 2125) $PN 19
J 2
(-6410 2135);
DISPLAY 0.489362 (-6410 2135);
PAINT MONO (-6410 2135);
FORCEPROP 0 LASTPIN (-6400 925) $PN 46
J 2
(-6410 935);
DISPLAY 0.489362 (-6410 935);
PAINT MONO (-6410 935);
FORCEPROP 0 LASTPIN (-6400 1025) $PN 45
J 2
(-6410 1035);
DISPLAY 0.489362 (-6410 1035);
PAINT MONO (-6410 1035);
FORCEPROP 0 LASTPIN (-6400 4325) $PN 25
J 2
(-6410 4335);
DISPLAY 0.489362 (-6410 4335);
PAINT MONO (-6410 4335);
FORCEPROP 0 LASTPIN (-6400 3225) $PN 40
J 2
(-6410 3235);
DISPLAY 0.489362 (-6410 3235);
PAINT MONO (-6410 3235);
FORCEPROP 2 LAST VALUE RAA229620GNP#HA0
J 0
(-5900 6500);
DISPLAY 0.489362 (-5900 6500);
PAINT SKYBLUE (-5900 6500);
FORCEPROP 1 LAST PART_NUMBER AR0T6GPV005
J 0
(-6250 6575);
DISPLAY 0.489362 (-6250 6575);
PAINT SKYBLUE (-6250 6575);
FORCEPROP 1 LAST MATERIAL IC
J 0
(-6250 6500);
DISPLAY 0.489362 (-6250 6500);
PAINT SKYBLUE (-6250 6500);
FORCEPROP 2 LAST PART_TYPE SMLF
J 0
(-5900 6550);
DISPLAY 0.638298 (-5900 6550);
FORCEPROP 1 LAST PATH I339
J 0
(-5700 3625);
DISPLAY 0.723404 (-5700 3625);
PAINT GREEN (-5700 3625);
DISPLAY INVISIBLE (-5700 3625);
FORCEPROP 1 LAST CDS_LMAN_SYM_OUTLINE -550,2850,500,-2850
J 0
(-5700 3625);
DISPLAY 0.468085 (-5700 3625);
PAINT GREEN (-5700 3625);
DISPLAY INVISIBLE (-5700 3625);
FORCEPROP 1 LAST NEEDS_NO_SIZE TRUE
J 0
(-5700 3625);
DISPLAY 0.723404 (-5700 3625);
PAINT GREEN (-5700 3625);
DISPLAY INVISIBLE (-5700 3625);
FORCEPROP 2 LAST CDS_LIB pure_quanta
J 0
(-5700 3625);
DISPLAY INVISIBLE (-5700 3625);
FORCEADD OFFPAGE..2
(-3675 5900);
FORCEPROP 2 LAST $XR4 182 
J 0
(-3006 5900);
DISPLAY 0.638298 (-3006 5900);
PAINT MONO (-3006 5900);
FORCEPROP 2 LAST $XR3 181 
J 0
(-3126 5900);
DISPLAY 0.638298 (-3126 5900);
PAINT MONO (-3126 5900);
FORCEPROP 2 LAST $XR2 179 
J 0
(-3246 5900);
DISPLAY 0.638298 (-3246 5900);
PAINT MONO (-3246 5900);
FORCEPROP 2 LAST $XR1 178 
J 0
(-3366 5900);
DISPLAY 0.638298 (-3366 5900);
PAINT MONO (-3366 5900);
FORCEPROP 2 LAST $XR0 177 
J 0
(-3486 5900);
DISPLAY 0.638298 (-3486 5900);
PAINT MONO (-3486 5900);
FORCEPROP 2 LAST PATH I340
J 0
(-3500 5975);
DISPLAY 1.021277 (-3500 5975);
DISPLAY INVISIBLE (-3500 5975);
FORCEPROP 1 LAST COMMENT_BODY TRUE
J 0
(-3720 5805);
DISPLAY 0.872340 (-3720 5805);
PAINT GREEN (-3720 5805);
DISPLAY INVISIBLE (-3720 5805);
FORCEPROP 1 LAST OFFPAGE TRUE
J 0
(-3350 5775);
DISPLAY 0.872340 (-3350 5775);
PAINT GREEN (-3350 5775);
DISPLAY INVISIBLE (-3350 5775);
FORCEPROP 2 LAST CDS_LIB standard
J 0
(-3675 5900);
DISPLAY INVISIBLE (-3675 5900);
FORCEADD Q_RES..1
(-8075 5625);
FORCEPROP 1 LAST LOCATION PR61
J 0
(-8125 5675);
DISPLAY 0.489362 (-8125 5675);
PAINT SKYBLUE (-8125 5675);
FORCEPROP 0 LAST $SEC 1
J 0
(-7675 5750);
DISPLAY 0.680851 (-7675 5750);
PAINT MONO (-7675 5750);
DISPLAY INVISIBLE (-7675 5750);
FORCEPROP 0 LAST CDS_SEC 1
J 0
(-7675 5750);
DISPLAY 1.021277 (-7675 5750);
DISPLAY INVISIBLE (-7675 5750);
FORCEPROP 1 LASTPIN (-8175 5625) $PN 1
J 0
(-8163 5637);
DISPLAY 0.489362 (-8163 5637);
PAINT MONO (-8163 5637);
FORCEPROP 1 LASTPIN (-7975 5625) $PN 2
J 0
(-8013 5637);
DISPLAY 0.489362 (-8013 5637);
PAINT MONO (-8013 5637);
FORCEPROP 1 LAST PACK_TYPE 0402LF
J 0
(-7450 5675);
DISPLAY 0.489362 (-7450 5675);
PAINT SKYBLUE (-7450 5675);
FORCEPROP 1 LAST PART_NUMBER CS00002JB38
J 0
(-7950 5675);
DISPLAY 0.489362 (-7950 5675);
PAINT SKYBLUE (-7950 5675);
FORCEPROP 1 LAST MATERIAL CHIP
J 0
(-7950 5725);
DISPLAY 0.489362 (-7950 5725);
PAINT SKYBLUE (-7950 5725);
FORCEPROP 1 LAST WATTAGE 1/16W
J 2
(-7675 5725);
DISPLAY 0.489362 (-7675 5725);
PAINT SKYBLUE (-7675 5725);
FORCEPROP 1 LAST TOLERANCE 5%
J 0
(-7525 5675);
DISPLAY 0.489362 (-7525 5675);
PAINT SKYBLUE (-7525 5675);
FORCEPROP 1 LAST VALUE 0
J 2
(-7550 5675);
DISPLAY 0.489362 (-7550 5675);
PAINT SKYBLUE (-7550 5675);
FORCEPROP 2 LAST CDS_LIB pure_quanta
J 0
(-8075 5625);
DISPLAY INVISIBLE (-8075 5625);
FORCEPROP 1 LAST PATH I348
J 0
(-8125 5775);
DISPLAY 0.978723 (-8125 5775);
PAINT WHITE (-8125 5775);
DISPLAY INVISIBLE (-8125 5775);
FORCEADD Q_RES..1
(-8075 5475);
FORCEPROP 1 LAST LOCATION PR62
J 0
(-8125 5525);
DISPLAY 0.489362 (-8125 5525);
PAINT SKYBLUE (-8125 5525);
FORCEPROP 0 LAST $SEC 1
J 0
(-7675 5600);
DISPLAY 0.680851 (-7675 5600);
PAINT MONO (-7675 5600);
DISPLAY INVISIBLE (-7675 5600);
FORCEPROP 0 LAST CDS_SEC 1
J 0
(-7675 5600);
DISPLAY 1.021277 (-7675 5600);
DISPLAY INVISIBLE (-7675 5600);
FORCEPROP 1 LASTPIN (-8175 5475) $PN 1
J 0
(-8163 5487);
DISPLAY 0.489362 (-8163 5487);
PAINT MONO (-8163 5487);
FORCEPROP 1 LASTPIN (-7975 5475) $PN 2
J 0
(-8013 5487);
DISPLAY 0.489362 (-8013 5487);
PAINT MONO (-8013 5487);
FORCEPROP 1 LAST TOLERANCE 5%
J 0
(-7550 5525);
DISPLAY 0.489362 (-7550 5525);
PAINT SKYBLUE (-7550 5525);
FORCEPROP 1 LAST PACK_TYPE 0402LF
J 0
(-7475 5525);
DISPLAY 0.489362 (-7475 5525);
PAINT SKYBLUE (-7475 5525);
FORCEPROP 1 LAST WATTAGE 1/16W
J 2
(-7675 5575);
DISPLAY 0.489362 (-7675 5575);
PAINT SKYBLUE (-7675 5575);
FORCEPROP 1 LAST MATERIAL CHIP
J 0
(-7950 5575);
DISPLAY 0.489362 (-7950 5575);
PAINT SKYBLUE (-7950 5575);
FORCEPROP 1 LAST VALUE 0
J 2
(-7575 5525);
DISPLAY 0.489362 (-7575 5525);
PAINT SKYBLUE (-7575 5525);
FORCEPROP 1 LAST PART_NUMBER CS00002JB38
J 0
(-7950 5525);
DISPLAY 0.489362 (-7950 5525);
PAINT SKYBLUE (-7950 5525);
FORCEPROP 2 LAST CDS_LIB pure_quanta
J 0
(-8075 5475);
DISPLAY INVISIBLE (-8075 5475);
FORCEPROP 1 LAST PATH I351
J 0
(-8125 5625);
DISPLAY 0.978723 (-8125 5625);
PAINT WHITE (-8125 5625);
DISPLAY INVISIBLE (-8125 5625);
FORCEADD OFFPAGE..5
(-10225 5625);
FORCEPROP 2 LAST $XR0 27 
J 0
(-10449 5625);
DISPLAY 0.638298 (-10449 5625);
PAINT MONO (-10449 5625);
FORCEPROP 2 LAST PATH I355
J 0
(-10175 5700);
DISPLAY 1.021277 (-10175 5700);
DISPLAY INVISIBLE (-10175 5700);
FORCEPROP 1 LAST COMMENT_BODY TRUE
J 0
(-10125 5550);
DISPLAY 0.872340 (-10125 5550);
PAINT GREEN (-10125 5550);
DISPLAY INVISIBLE (-10125 5550);
FORCEPROP 1 LAST OFFPAGE TRUE
J 0
(-9900 5500);
DISPLAY 0.872340 (-9900 5500);
PAINT GREEN (-9900 5500);
DISPLAY INVISIBLE (-9900 5500);
FORCEPROP 2 LAST CDS_LIB standard
J 0
(-10225 5625);
DISPLAY INVISIBLE (-10225 5625);
FORCEADD Q_RES..1
(-7350 5075);
FORCEPROP 1 LAST LOCATION PR72
J 0
(-7550 5075);
DISPLAY 0.489362 (-7550 5075);
PAINT SKYBLUE (-7550 5075);
FORCEPROP 0 LAST $SEC 1
J 0
(-7550 5100);
DISPLAY 0.680851 (-7550 5100);
PAINT MONO (-7550 5100);
DISPLAY INVISIBLE (-7550 5100);
FORCEPROP 0 LAST CDS_SEC 1
J 0
(-7550 5100);
DISPLAY 1.021277 (-7550 5100);
DISPLAY INVISIBLE (-7550 5100);
FORCEPROP 1 LASTPIN (-7450 5075) $PN 1
J 0
(-7438 5087);
DISPLAY 0.489362 (-7438 5087);
PAINT MONO (-7438 5087);
FORCEPROP 1 LASTPIN (-7250 5075) $PN 2
J 0
(-7288 5087);
DISPLAY 0.489362 (-7288 5087);
PAINT MONO (-7288 5087);
FORCEPROP 1 LAST MATERIAL CHIP
J 0
(-7675 5025);
DISPLAY 0.489362 (-7675 5025);
PAINT SKYBLUE (-7675 5025);
FORCEPROP 1 LAST TOLERANCE 5%
J 0
(-7325 5025);
DISPLAY 0.489362 (-7325 5025);
PAINT SKYBLUE (-7325 5025);
FORCEPROP 1 LAST VALUE 0
J 2
(-7350 5025);
DISPLAY 0.489362 (-7350 5025);
PAINT SKYBLUE (-7350 5025);
FORCEPROP 1 LAST PACK_TYPE 0402LF
J 0
(-7250 5025);
DISPLAY 0.489362 (-7250 5025);
PAINT SKYBLUE (-7250 5025);
FORCEPROP 1 LAST WATTAGE 1/16W
J 2
(-7425 5025);
DISPLAY 0.489362 (-7425 5025);
PAINT SKYBLUE (-7425 5025);
FORCEPROP 1 LAST PART_NUMBER CS00002JB38
J 0
(-8025 5025);
DISPLAY 0.489362 (-8025 5025);
PAINT SKYBLUE (-8025 5025);
FORCEPROP 2 LAST CDS_LIB pure_quanta
J 0
(-7350 5075);
DISPLAY INVISIBLE (-7350 5075);
FORCEPROP 1 LAST PATH I366
J 0
(-7400 5225);
DISPLAY 0.978723 (-7400 5225);
PAINT WHITE (-7400 5225);
DISPLAY INVISIBLE (-7400 5225);
FORCEADD Q_RES..1
(-7350 4925);
FORCEPROP 1 LAST LOCATION PR73
J 0
(-7550 4925);
DISPLAY 0.489362 (-7550 4925);
PAINT SKYBLUE (-7550 4925);
FORCEPROP 0 LAST $SEC 1
J 0
(-7550 4950);
DISPLAY 0.680851 (-7550 4950);
PAINT MONO (-7550 4950);
DISPLAY INVISIBLE (-7550 4950);
FORCEPROP 0 LAST CDS_SEC 1
J 0
(-7550 4950);
DISPLAY 1.021277 (-7550 4950);
DISPLAY INVISIBLE (-7550 4950);
FORCEPROP 1 LASTPIN (-7450 4925) $PN 1
J 0
(-7438 4937);
DISPLAY 0.489362 (-7438 4937);
PAINT MONO (-7438 4937);
FORCEPROP 1 LASTPIN (-7250 4925) $PN 2
J 0
(-7288 4937);
DISPLAY 0.489362 (-7288 4937);
PAINT MONO (-7288 4937);
FORCEPROP 1 LAST VALUE 0
J 2
(-7350 4875);
DISPLAY 0.489362 (-7350 4875);
PAINT SKYBLUE (-7350 4875);
FORCEPROP 1 LAST PACK_TYPE 0402LF
J 0
(-7250 4875);
DISPLAY 0.489362 (-7250 4875);
PAINT SKYBLUE (-7250 4875);
FORCEPROP 1 LAST TOLERANCE 5%
J 0
(-7325 4875);
DISPLAY 0.489362 (-7325 4875);
PAINT SKYBLUE (-7325 4875);
FORCEPROP 1 LAST WATTAGE 1/16W
J 2
(-7425 4875);
DISPLAY 0.489362 (-7425 4875);
PAINT SKYBLUE (-7425 4875);
FORCEPROP 1 LAST MATERIAL CHIP
J 0
(-7675 4875);
DISPLAY 0.489362 (-7675 4875);
PAINT SKYBLUE (-7675 4875);
FORCEPROP 1 LAST PART_NUMBER CS00002JB38
J 0
(-8025 4875);
DISPLAY 0.489362 (-8025 4875);
PAINT SKYBLUE (-8025 4875);
FORCEPROP 2 LAST CDS_LIB pure_quanta
J 0
(-7350 4925);
DISPLAY INVISIBLE (-7350 4925);
FORCEPROP 1 LAST PATH I367
J 0
(-7400 5075);
DISPLAY 0.978723 (-7400 5075);
PAINT WHITE (-7400 5075);
DISPLAY INVISIBLE (-7400 5075);
FORCEADD OFFPAGE..5
(-8400 4925);
FORCEPROP 2 LAST $XR1 81 
J 0
(-8744 4925);
DISPLAY 0.638298 (-8744 4925);
PAINT MONO (-8744 4925);
FORCEPROP 2 LAST $XR0 82 
J 0
(-8654 4925);
DISPLAY 0.638298 (-8654 4925);
PAINT MONO (-8654 4925);
FORCEPROP 2 LAST PATH I368
J 0
(-8350 5000);
DISPLAY 1.021277 (-8350 5000);
DISPLAY INVISIBLE (-8350 5000);
FORCEPROP 1 LAST COMMENT_BODY TRUE
J 0
(-8300 4850);
DISPLAY 0.872340 (-8300 4850);
PAINT GREEN (-8300 4850);
DISPLAY INVISIBLE (-8300 4850);
FORCEPROP 1 LAST OFFPAGE TRUE
J 0
(-8075 4800);
DISPLAY 0.872340 (-8075 4800);
PAINT GREEN (-8075 4800);
DISPLAY INVISIBLE (-8075 4800);
FORCEPROP 2 LAST CDS_LIB standard
J 0
(-8400 4925);
DISPLAY INVISIBLE (-8400 4925);
FORCEADD OFFPAGE..5
(-8050 2375);
FORCEPROP 2 LAST $XR0 81 
J 0
(-8304 2375);
DISPLAY 0.638298 (-8304 2375);
PAINT MONO (-8304 2375);
FORCEPROP 2 LAST PATH I371
J 0
(-8000 2450);
DISPLAY 1.021277 (-8000 2450);
DISPLAY INVISIBLE (-8000 2450);
FORCEPROP 1 LAST COMMENT_BODY TRUE
J 0
(-7950 2300);
DISPLAY 0.872340 (-7950 2300);
PAINT GREEN (-7950 2300);
DISPLAY INVISIBLE (-7950 2300);
FORCEPROP 1 LAST OFFPAGE TRUE
J 0
(-7725 2250);
DISPLAY 0.872340 (-7725 2250);
PAINT GREEN (-7725 2250);
DISPLAY INVISIBLE (-7725 2250);
FORCEPROP 2 LAST CDS_LIB standard
J 0
(-8050 2375);
DISPLAY INVISIBLE (-8050 2375);
FORCEADD Q_RES..1
(-7325 2375);
FORCEPROP 1 LAST LOCATION PR64
J 0
(-7375 2425);
DISPLAY 0.489362 (-7375 2425);
PAINT SKYBLUE (-7375 2425);
FORCEPROP 0 LAST $SEC 1
J 0
(-7375 2450);
DISPLAY 0.680851 (-7375 2450);
PAINT MONO (-7375 2450);
DISPLAY INVISIBLE (-7375 2450);
FORCEPROP 0 LAST CDS_SEC 1
J 0
(-7375 2450);
DISPLAY 1.021277 (-7375 2450);
DISPLAY INVISIBLE (-7375 2450);
FORCEPROP 1 LASTPIN (-7425 2375) $PN 1
J 0
(-7413 2387);
DISPLAY 0.489362 (-7413 2387);
PAINT MONO (-7413 2387);
FORCEPROP 1 LASTPIN (-7225 2375) $PN 2
J 0
(-7263 2387);
DISPLAY 0.489362 (-7263 2387);
PAINT MONO (-7263 2387);
FORCEPROP 1 LAST TOLERANCE 5%
J 0
(-7300 2325);
DISPLAY 0.489362 (-7300 2325);
PAINT SKYBLUE (-7300 2325);
FORCEPROP 1 LAST WATTAGE 1/16W
J 2
(-7400 2325);
DISPLAY 0.489362 (-7400 2325);
PAINT SKYBLUE (-7400 2325);
FORCEPROP 1 LAST PART_NUMBER CS00002JB38
J 0
(-8000 2325);
DISPLAY 0.489362 (-8000 2325);
PAINT SKYBLUE (-8000 2325);
FORCEPROP 1 LAST MATERIAL CHIP
J 0
(-7650 2325);
DISPLAY 0.489362 (-7650 2325);
PAINT SKYBLUE (-7650 2325);
FORCEPROP 1 LAST VALUE 0
J 2
(-7325 2325);
DISPLAY 0.489362 (-7325 2325);
PAINT SKYBLUE (-7325 2325);
FORCEPROP 1 LAST PACK_TYPE 0402LF
J 0
(-7225 2325);
DISPLAY 0.489362 (-7225 2325);
PAINT SKYBLUE (-7225 2325);
FORCEPROP 2 LAST CDS_LIB pure_quanta
J 0
(-7325 2375);
DISPLAY INVISIBLE (-7325 2375);
FORCEPROP 1 LAST PATH I372
J 0
(-7375 2525);
DISPLAY 0.978723 (-7375 2525);
PAINT WHITE (-7375 2525);
DISPLAY INVISIBLE (-7375 2525);
FORCEADD Q_RES..1
(-7475 2675);
FORCEPROP 1 LAST LOCATION PR70
J 0
(-7850 2700);
DISPLAY 0.489362 (-7850 2700);
PAINT SKYBLUE (-7850 2700);
FORCEPROP 0 LAST $SEC 1
J 0
(-7725 2775);
DISPLAY 0.680851 (-7725 2775);
PAINT MONO (-7725 2775);
DISPLAY INVISIBLE (-7725 2775);
FORCEPROP 0 LAST CDS_SEC 1
J 0
(-7725 2775);
DISPLAY 1.021277 (-7725 2775);
DISPLAY INVISIBLE (-7725 2775);
FORCEPROP 1 LASTPIN (-7575 2675) $PN 1
J 0
(-7563 2687);
DISPLAY 0.489362 (-7563 2687);
PAINT MONO (-7563 2687);
FORCEPROP 1 LASTPIN (-7375 2675) $PN 2
J 0
(-7413 2687);
DISPLAY 0.489362 (-7413 2687);
PAINT MONO (-7413 2687);
FORCEPROP 1 LAST WATTAGE 1/16W
J 2
(-7200 2700);
DISPLAY 0.489362 (-7200 2700);
PAINT SKYBLUE (-7200 2700);
FORCEPROP 1 LAST MATERIAL CHIP
J 0
(-7425 2700);
DISPLAY 0.489362 (-7425 2700);
PAINT SKYBLUE (-7425 2700);
FORCEPROP 1 LAST TOLERANCE 1%
J 0
(-7650 2700);
DISPLAY 0.489362 (-7650 2700);
PAINT SKYBLUE (-7650 2700);
FORCEPROP 1 LAST VALUE 1K
J 2
(-7675 2700);
DISPLAY 0.489362 (-7675 2700);
PAINT SKYBLUE (-7675 2700);
FORCEPROP 1 LAST PART_NUMBER TMP_QCS21002FB24
J 0
(-7725 2750);
DISPLAY 0.489362 (-7725 2750);
PAINT SKYBLUE (-7725 2750);
FORCEPROP 1 LAST PACK_TYPE 0402LF
J 0
(-7575 2700);
DISPLAY 0.489362 (-7575 2700);
PAINT SKYBLUE (-7575 2700);
FORCEPROP 2 LAST CDS_LIB pure_quanta
J 0
(-7475 2675);
DISPLAY INVISIBLE (-7475 2675);
FORCEPROP 1 LAST PATH I378
J 0
(-7525 2825);
DISPLAY 0.978723 (-7525 2825);
PAINT WHITE (-7525 2825);
DISPLAY INVISIBLE (-7525 2825);
FORCEADD Q_RES..1
(-7325 2525);
FORCEPROP 1 LAST LOCATION PR63
J 0
(-7375 2575);
DISPLAY 0.489362 (-7375 2575);
PAINT SKYBLUE (-7375 2575);
FORCEPROP 0 LAST $SEC 1
J 0
(-7375 2600);
DISPLAY 0.680851 (-7375 2600);
PAINT MONO (-7375 2600);
DISPLAY INVISIBLE (-7375 2600);
FORCEPROP 0 LAST CDS_SEC 1
J 0
(-7375 2600);
DISPLAY 1.021277 (-7375 2600);
DISPLAY INVISIBLE (-7375 2600);
FORCEPROP 1 LASTPIN (-7425 2525) $PN 1
J 0
(-7413 2537);
DISPLAY 0.489362 (-7413 2537);
PAINT MONO (-7413 2537);
FORCEPROP 1 LASTPIN (-7225 2525) $PN 2
J 0
(-7263 2537);
DISPLAY 0.489362 (-7263 2537);
PAINT MONO (-7263 2537);
FORCEPROP 1 LAST PACK_TYPE 0402LF
J 0
(-7225 2475);
DISPLAY 0.489362 (-7225 2475);
PAINT SKYBLUE (-7225 2475);
FORCEPROP 1 LAST WATTAGE 1/16W
J 2
(-7400 2475);
DISPLAY 0.489362 (-7400 2475);
PAINT SKYBLUE (-7400 2475);
FORCEPROP 1 LAST MATERIAL CHIP
J 0
(-7650 2475);
DISPLAY 0.489362 (-7650 2475);
PAINT SKYBLUE (-7650 2475);
FORCEPROP 1 LAST TOLERANCE 5%
J 0
(-7300 2475);
DISPLAY 0.489362 (-7300 2475);
PAINT SKYBLUE (-7300 2475);
FORCEPROP 1 LAST VALUE 0
J 2
(-7325 2475);
DISPLAY 0.489362 (-7325 2475);
PAINT SKYBLUE (-7325 2475);
FORCEPROP 1 LAST PART_NUMBER CS00002JB38
J 0
(-8000 2475);
DISPLAY 0.489362 (-8000 2475);
PAINT SKYBLUE (-8000 2475);
FORCEPROP 2 LAST CDS_LIB pure_quanta
J 0
(-7325 2525);
DISPLAY INVISIBLE (-7325 2525);
FORCEPROP 1 LAST PATH I379
J 0
(-7375 2675);
DISPLAY 0.978723 (-7375 2675);
PAINT WHITE (-7375 2675);
DISPLAY INVISIBLE (-7375 2675);
FORCEADD Q_CAP..2
(-7025 2000);
FORCEPROP 1 LAST LOCATION PC73
J 1
(-7350 2050);
DISPLAY 0.489362 (-7350 2050);
PAINT SKYBLUE (-7350 2050);
FORCEPROP 0 LAST $SEC 1
J 0
(-6450 2075);
DISPLAY 0.680851 (-6450 2075);
PAINT MONO (-6450 2075);
DISPLAY INVISIBLE (-6450 2075);
FORCEPROP 0 LAST CDS_SEC 1
J 0
(-6450 2075);
DISPLAY 1.021277 (-6450 2075);
DISPLAY INVISIBLE (-6450 2075);
FORCEPROP 1 LASTPIN (-7125 2000) $PN 1
J 0
(-7135 2015);
DISPLAY 0.489362 (-7135 2015);
PAINT MONO (-7135 2015);
FORCEPROP 1 LASTPIN (-6925 2000) $PN 2
J 0
(-6940 2015);
DISPLAY 0.489362 (-6940 2015);
PAINT MONO (-6940 2015);
FORCEPROP 1 LAST VALUE 1UF
J 2
(-7225 2050);
DISPLAY 0.489362 (-7225 2050);
PAINT SKYBLUE (-7225 2050);
FORCEPROP 1 LAST MATERIAL X7R
J 0
(-7050 2050);
DISPLAY 0.489362 (-7050 2050);
PAINT SKYBLUE (-7050 2050);
FORCEPROP 1 LAST TOLERANCE 10%
J 2
(-6450 2050);
DISPLAY 0.489362 (-6450 2050);
PAINT SKYBLUE (-6450 2050);
FORCEPROP 1 LAST PART_NUMBER CH5101K1B01
J 1
(-6800 2050);
DISPLAY 0.489362 (-6800 2050);
PAINT SKYBLUE (-6800 2050);
FORCEPROP 1 LAST VOLTAGE 6.3V
J 0
(-7175 2050);
DISPLAY 0.489362 (-7175 2050);
PAINT SKYBLUE (-7175 2050);
FORCEPROP 1 LAST PACK_TYPE 0402
J 1
(-6600 2050);
DISPLAY 0.489362 (-6600 2050);
PAINT SKYBLUE (-6600 2050);
FORCEPROP 2 LAST CDS_LIB pure_quanta
J 0
(-7025 2000);
DISPLAY INVISIBLE (-7025 2000);
FORCEPROP 1 LAST PATH I380
J 0
(-7025 2200);
DISPLAY 0.978723 (-7025 2200);
PAINT WHITE (-7025 2200);
DISPLAY INVISIBLE (-7025 2200);
FORCEADD UNIVERSAL_GND..1
R 1
(-6625 2000);
FORCEPROP 3 LASTPIN (-6675 2000) SIG_NAME GND\g
J 0
(-6665 2010);
DISPLAY 0.659574 (-6665 2010);
PAINT MONO (-6665 2010);
DISPLAY INVISIBLE (-6665 2010);
FORCEPROP 2 LAST CDS_LIB pure_quanta_power
J 0
(-6625 2000);
DISPLAY INVISIBLE (-6625 2000);
FORCEPROP 1 LAST PATH I381
R 1
J 0
(-6625 2075);
DISPLAY 0.872340 (-6625 2075);
PAINT AQUA (-6625 2075);
DISPLAY INVISIBLE (-6625 2075);
FORCEPROP 1 LAST HDL_POWER GND
R 1
J 1
(-6550 2025);
DISPLAY 0.872340 (-6550 2025);
PAINT GREEN (-6550 2025);
DISPLAY INVISIBLE (-6550 2025);
FORCEADD VCC_CORE..1
(-7575 2075);
FORCEPROP 3 LASTPIN (-7575 2025) SIG_NAME PVDD18_S5_P0\g
J 0
(-7565 2035);
DISPLAY 0.659574 (-7565 2035);
PAINT MONO (-7565 2035);
DISPLAY INVISIBLE (-7565 2035);
FORCEPROP 1 LAST HDL_POWER PVDD18_S5_P0
J 1
(-7575 2125);
DISPLAY 0.489362 (-7575 2125);
PAINT GREEN (-7575 2125);
FORCEPROP 2 LAST CDS_LIB pure_quanta_power
J 0
(-7575 2075);
DISPLAY INVISIBLE (-7575 2075);
FORCEPROP 1 LAST PATH I382
J 0
(-7525 2100);
DISPLAY 0.872340 (-7525 2100);
PAINT AQUA (-7525 2100);
DISPLAY INVISIBLE (-7525 2100);
FORCEADD OFFPAGE..1
(-8050 2525);
FORCEPROP 2 LAST $XR0 77 
J 0
(-8271 2525);
DISPLAY 0.638298 (-8271 2525);
PAINT MONO (-8271 2525);
FORCEPROP 2 LAST PATH I384
J 0
(-8000 2600);
DISPLAY 1.021277 (-8000 2600);
DISPLAY INVISIBLE (-8000 2600);
FORCEPROP 1 LAST COMMENT_BODY TRUE
J 0
(-7925 2425);
DISPLAY 0.872340 (-7925 2425);
PAINT GREEN (-7925 2425);
DISPLAY INVISIBLE (-7925 2425);
FORCEPROP 1 LAST OFFPAGE TRUE
J 0
(-7725 2400);
DISPLAY 0.872340 (-7725 2400);
PAINT GREEN (-7725 2400);
DISPLAY INVISIBLE (-7725 2400);
FORCEPROP 2 LAST CDS_LIB standard
J 0
(-8050 2525);
DISPLAY INVISIBLE (-8050 2525);
FORCEADD Q_RES..1
(-6775 2250);
FORCEPROP 1 LAST LOCATION PR75
J 0
(-6825 2200);
DISPLAY 0.489362 (-6825 2200);
PAINT SKYBLUE (-6825 2200);
FORCEPROP 0 LAST $SEC 1
J 0
(-7025 2350);
DISPLAY 0.680851 (-7025 2350);
PAINT MONO (-7025 2350);
DISPLAY INVISIBLE (-7025 2350);
FORCEPROP 0 LAST CDS_SEC 1
J 0
(-7025 2350);
DISPLAY 1.021277 (-7025 2350);
DISPLAY INVISIBLE (-7025 2350);
FORCEPROP 1 LASTPIN (-6875 2250) $PN 1
J 0
(-6863 2262);
DISPLAY 0.489362 (-6863 2262);
PAINT MONO (-6863 2262);
FORCEPROP 1 LASTPIN (-6675 2250) $PN 2
J 0
(-6713 2262);
DISPLAY 0.489362 (-6713 2262);
PAINT MONO (-6713 2262);
FORCEPROP 1 LAST PART_NUMBER TMP_QCS21002FB24
J 0
(-7025 2325);
DISPLAY 0.489362 (-7025 2325);
PAINT SKYBLUE (-7025 2325);
FORCEPROP 1 LAST WATTAGE 1/16W
J 2
(-6500 2275);
DISPLAY 0.489362 (-6500 2275);
PAINT SKYBLUE (-6500 2275);
FORCEPROP 1 LAST MATERIAL CHIP
J 0
(-6725 2275);
DISPLAY 0.489362 (-6725 2275);
PAINT SKYBLUE (-6725 2275);
FORCEPROP 1 LAST TOLERANCE 1%
J 0
(-6950 2275);
DISPLAY 0.489362 (-6950 2275);
PAINT SKYBLUE (-6950 2275);
FORCEPROP 1 LAST VALUE 1K
J 2
(-6975 2275);
DISPLAY 0.489362 (-6975 2275);
PAINT SKYBLUE (-6975 2275);
FORCEPROP 1 LAST PACK_TYPE 0402LF
J 0
(-6875 2275);
DISPLAY 0.489362 (-6875 2275);
PAINT SKYBLUE (-6875 2275);
FORCEPROP 2 LAST CDS_LIB pure_quanta
J 0
(-6775 2250);
DISPLAY INVISIBLE (-6775 2250);
FORCEPROP 1 LAST PATH I385
J 0
(-6825 2400);
DISPLAY 0.978723 (-6825 2400);
PAINT WHITE (-6825 2400);
DISPLAY INVISIBLE (-6825 2400);
FORCEADD VCC_CORE..1
(-9200 2650);
FORCEPROP 3 LASTPIN (-9200 2600) SIG_NAME P3V3_STBY\g
J 0
(-9190 2610);
DISPLAY 0.659574 (-9190 2610);
PAINT MONO (-9190 2610);
DISPLAY INVISIBLE (-9190 2610);
FORCEPROP 1 LAST HDL_POWER P3V3_STBY
J 1
(-9200 2700);
DISPLAY 0.489362 (-9200 2700);
PAINT GREEN (-9200 2700);
FORCEPROP 2 LAST CDS_LIB pure_quanta_power
J 0
(-9200 2650);
DISPLAY INVISIBLE (-9200 2650);
FORCEPROP 1 LAST PATH I390
J 0
(-9150 2675);
DISPLAY 0.872340 (-9150 2675);
PAINT AQUA (-9150 2675);
DISPLAY INVISIBLE (-9150 2675);
FORCEADD MOSFET_N..1
(-9250 1825);
FORCEPROP 1 LAST LOCATION PQ14
J 0
(-9125 1850);
DISPLAY 0.489362 (-9125 1850);
PAINT SKYBLUE (-9125 1850);
FORCEPROP 0 LAST $SEC 1
J 0
(-9100 1875);
DISPLAY 0.680851 (-9100 1875);
PAINT MONO (-9100 1875);
DISPLAY INVISIBLE (-9100 1875);
FORCEPROP 0 LAST CDS_SEC 1
J 0
(-9100 1875);
DISPLAY 1.021277 (-9100 1875);
DISPLAY INVISIBLE (-9100 1875);
FORCEPROP 1 LASTPIN (-9200 1925) $PN D
R 1
J 0
(-9200 1918);
DISPLAY 0.489362 (-9200 1918);
PAINT MONO (-9200 1918);
FORCEPROP 1 LASTPIN (-9350 1725) $PN G
J 2
(-9340 1728);
DISPLAY 0.489362 (-9340 1728);
PAINT MONO (-9340 1728);
FORCEPROP 1 LASTPIN (-9200 1625) $PN S
R 1
J 2
(-9200 1638);
DISPLAY 0.489362 (-9200 1638);
PAINT MONO (-9200 1638);
FORCEPROP 1 LAST PART_NUMBER BAM138K0000
J 0
(-9125 1750);
DISPLAY 0.489362 (-9125 1750);
PAINT SKYBLUE (-9125 1750);
FORCEPROP 1 LAST VALUE BSS138K
J 0
(-9125 1800);
DISPLAY 0.489362 (-9125 1800);
PAINT SKYBLUE (-9125 1800);
FORCEPROP 1 LAST MATERIAL IC
J 0
(-9125 1700);
DISPLAY 0.489362 (-9125 1700);
PAINT SKYBLUE (-9125 1700);
FORCEPROP 0 LAST MANUF_PN BSS138K
J 0
(-9075 1700);
DISPLAY 1.021277 (-9075 1700);
DISPLAY INVISIBLE (-9075 1700);
FORCEPROP 2 LAST CDS_LIB pure_quanta
J 0
(-9250 1825);
DISPLAY INVISIBLE (-9250 1825);
FORCEPROP 1 LAST CDS_LMAN_SYM_OUTLINE -50,50,100,-150
J 0
(-9250 1825);
DISPLAY 0.468085 (-9250 1825);
PAINT GREEN (-9250 1825);
DISPLAY INVISIBLE (-9250 1825);
FORCEPROP 0 LAST PATH I391
J 0
(-9075 1750);
DISPLAY 1.021277 (-9075 1750);
DISPLAY INVISIBLE (-9075 1750);
FORCEPROP 1 LAST PACK_TYPE SMLF
J 0
(-9225 1575);
DISPLAY 0.723404 (-9225 1575);
PAINT SKYBLUE (-9225 1575);
DISPLAY INVISIBLE (-9225 1575);
FORCEADD Q_RES..2
(-9200 2350);
FORCEPROP 1 LAST LOCATION PR55
J 0
(-9150 2475);
DISPLAY 0.489362 (-9150 2475);
PAINT SKYBLUE (-9150 2475);
FORCEPROP 0 LAST $SEC 1
J 0
(-9150 2500);
DISPLAY 0.680851 (-9150 2500);
PAINT MONO (-9150 2500);
DISPLAY INVISIBLE (-9150 2500);
FORCEPROP 0 LAST CDS_SEC 1
J 0
(-9450 2450);
DISPLAY 1.021277 (-9450 2450);
DISPLAY INVISIBLE (-9450 2450);
FORCEPROP 1 LASTPIN (-9200 2450) $PN 1
J 0
(-9195 2412);
DISPLAY 0.489362 (-9195 2412);
PAINT MONO (-9195 2412);
FORCEPROP 1 LASTPIN (-9200 2250) $PN 2
J 0
(-9195 2260);
DISPLAY 0.489362 (-9195 2260);
PAINT MONO (-9195 2260);
FORCEPROP 1 LAST WATTAGE 1/16W
J 0
(-9150 2325);
DISPLAY 0.489362 (-9150 2325);
PAINT SKYBLUE (-9150 2325);
FORCEPROP 1 LAST MATERIAL CHIP
J 0
(-9150 2275);
DISPLAY 0.489362 (-9150 2275);
PAINT SKYBLUE (-9150 2275);
FORCEPROP 1 LAST TOLERANCE 1%
J 0
(-9150 2375);
DISPLAY 0.489362 (-9150 2375);
PAINT SKYBLUE (-9150 2375);
FORCEPROP 1 LAST VALUE 1K
J 0
(-9150 2425);
DISPLAY 0.489362 (-9150 2425);
PAINT SKYBLUE (-9150 2425);
FORCEPROP 1 LAST PACK_TYPE 0402LF
J 0
(-9150 2225);
DISPLAY 0.489362 (-9150 2225);
PAINT SKYBLUE (-9150 2225);
FORCEPROP 2 LAST CDS_LIB pure_quanta
J 0
(-9200 2350);
DISPLAY INVISIBLE (-9200 2350);
FORCEPROP 1 LAST PATH I392
J 0
(-9150 2525);
DISPLAY 0.978723 (-9150 2525);
PAINT WHITE (-9150 2525);
DISPLAY INVISIBLE (-9150 2525);
FORCEPROP 1 LAST PART_NUMBER TMP_QCS21002FB24
J 0
(-9160 2225);
DISPLAY 0.489362 (-9160 2225);
PAINT SKYBLUE (-9160 2225);
DISPLAY INVISIBLE (-9160 2225);
FORCEADD UNIVERSAL_GND..1
(-9200 1450);
FORCEPROP 3 LASTPIN (-9200 1500) SIG_NAME GND\g
J 0
(-9190 1510);
DISPLAY 0.659574 (-9190 1510);
PAINT MONO (-9190 1510);
DISPLAY INVISIBLE (-9190 1510);
FORCEPROP 2 LAST CDS_LIB pure_quanta_power
J 0
(-9200 1450);
DISPLAY INVISIBLE (-9200 1450);
FORCEPROP 1 LAST PATH I393
J 0
(-9125 1450);
DISPLAY 0.872340 (-9125 1450);
PAINT AQUA (-9125 1450);
DISPLAY INVISIBLE (-9125 1450);
FORCEPROP 1 LAST HDL_POWER GND
J 1
(-9175 1375);
DISPLAY 0.872340 (-9175 1375);
PAINT GREEN (-9175 1375);
DISPLAY INVISIBLE (-9175 1375);
FORCEADD Q_RES..2
(-8550 1675);
FORCEPROP 1 LAST LOCATION PR67
J 0
(-8500 1725);
DISPLAY 0.489362 (-8500 1725);
PAINT SKYBLUE (-8500 1725);
FORCEPROP 0 LAST $SEC 1
J 0
(-8525 1750);
DISPLAY 0.680851 (-8525 1750);
PAINT MONO (-8525 1750);
DISPLAY INVISIBLE (-8525 1750);
FORCEPROP 0 LAST CDS_SEC 1
J 0
(-8525 1750);
DISPLAY 1.021277 (-8525 1750);
DISPLAY INVISIBLE (-8525 1750);
FORCEPROP 1 LASTPIN (-8550 1775) $PN 1
J 0
(-8545 1737);
DISPLAY 0.489362 (-8545 1737);
PAINT MONO (-8545 1737);
FORCEPROP 1 LASTPIN (-8550 1575) $PN 2
J 0
(-8545 1585);
DISPLAY 0.489362 (-8545 1585);
PAINT MONO (-8545 1585);
FORCEPROP 1 LAST PART_NUMBER CS21962FB08
J 0
(-8500 1600);
DISPLAY 0.489362 (-8500 1600);
PAINT SKYBLUE (-8500 1600);
FORCEPROP 1 LAST WATTAGE 1/16W
J 0
(-8500 1650);
DISPLAY 0.489362 (-8500 1650);
PAINT SKYBLUE (-8500 1650);
FORCEPROP 1 LAST MATERIAL CHIP
J 0
(-8500 1625);
DISPLAY 0.489362 (-8500 1625);
PAINT SKYBLUE (-8500 1625);
FORCEPROP 1 LAST TOLERANCE 1%
J 0
(-8500 1675);
DISPLAY 0.489362 (-8500 1675);
PAINT SKYBLUE (-8500 1675);
FORCEPROP 1 LAST VALUE 1.96K
J 0
(-8500 1700);
DISPLAY 0.489362 (-8500 1700);
PAINT SKYBLUE (-8500 1700);
FORCEPROP 1 LAST PACK_TYPE 0402LF
J 0
(-8500 1575);
DISPLAY 0.489362 (-8500 1575);
PAINT SKYBLUE (-8500 1575);
FORCEPROP 2 LAST CDS_LIB pure_quanta
J 0
(-8550 1675);
DISPLAY INVISIBLE (-8550 1675);
FORCEPROP 1 LAST PATH I394
J 0
(-8500 1850);
DISPLAY 0.978723 (-8500 1850);
PAINT WHITE (-8500 1850);
DISPLAY INVISIBLE (-8500 1850);
FORCEADD Q_RES..1
(-9950 1725);
FORCEPROP 1 LAST LOCATION PR47
J 0
(-10000 1775);
DISPLAY 0.489362 (-10000 1775);
PAINT SKYBLUE (-10000 1775);
FORCEPROP 0 LAST $SEC 1
J 0
(-9600 1875);
DISPLAY 0.680851 (-9600 1875);
PAINT MONO (-9600 1875);
DISPLAY INVISIBLE (-9600 1875);
FORCEPROP 0 LAST CDS_SEC 1
J 0
(-9600 1875);
DISPLAY 1.021277 (-9600 1875);
DISPLAY INVISIBLE (-9600 1875);
FORCEPROP 1 LASTPIN (-10050 1725) $PN 1
J 0
(-10038 1737);
DISPLAY 0.489362 (-10038 1737);
PAINT MONO (-10038 1737);
FORCEPROP 1 LASTPIN (-9850 1725) $PN 2
J 0
(-9888 1737);
DISPLAY 0.489362 (-9888 1737);
PAINT MONO (-9888 1737);
FORCEPROP 1 LAST WATTAGE 1/16W
J 2
(-9825 1675);
DISPLAY 0.489362 (-9825 1675);
PAINT SKYBLUE (-9825 1675);
FORCEPROP 1 LAST MATERIAL CHIP
J 0
(-10075 1675);
DISPLAY 0.489362 (-10075 1675);
PAINT SKYBLUE (-10075 1675);
FORCEPROP 1 LAST TOLERANCE 5%
J 0
(-10025 1575);
DISPLAY 0.489362 (-10025 1575);
PAINT SKYBLUE (-10025 1575);
FORCEPROP 1 LAST VALUE 0
J 2
(-10050 1575);
DISPLAY 0.489362 (-10050 1575);
PAINT SKYBLUE (-10050 1575);
FORCEPROP 1 LAST PART_NUMBER CS00002JB38
J 0
(-10075 1625);
DISPLAY 0.489362 (-10075 1625);
PAINT SKYBLUE (-10075 1625);
FORCEPROP 1 LAST PACK_TYPE 0402LF
J 0
(-9950 1575);
DISPLAY 0.489362 (-9950 1575);
PAINT SKYBLUE (-9950 1575);
FORCEPROP 2 LAST CDS_LIB pure_quanta
J 0
(-9950 1725);
DISPLAY INVISIBLE (-9950 1725);
FORCEPROP 1 LAST PATH I395
J 0
(-10000 1875);
DISPLAY 0.978723 (-10000 1875);
PAINT WHITE (-10000 1875);
DISPLAY INVISIBLE (-10000 1875);
FORCEADD OFFPAGE..1
(-10400 1725);
FORCEPROP 2 LAST $XR0 80 
J 0
(-10681 1725);
DISPLAY 0.638298 (-10681 1725);
PAINT MONO (-10681 1725);
FORCEPROP 2 LAST PATH I396
J 0
(-10350 1800);
DISPLAY 1.021277 (-10350 1800);
DISPLAY INVISIBLE (-10350 1800);
FORCEPROP 1 LAST COMMENT_BODY TRUE
J 0
(-10275 1625);
DISPLAY 0.872340 (-10275 1625);
PAINT GREEN (-10275 1625);
DISPLAY INVISIBLE (-10275 1625);
FORCEPROP 1 LAST OFFPAGE TRUE
J 0
(-10075 1600);
DISPLAY 0.872340 (-10075 1600);
PAINT GREEN (-10075 1600);
DISPLAY INVISIBLE (-10075 1600);
FORCEPROP 2 LAST CDS_LIB standard
J 0
(-10400 1725);
DISPLAY INVISIBLE (-10400 1725);
FORCEADD Q_CAP..1
(-9700 1550);
FORCEPROP 1 LAST LOCATION PC66
J 0
(-9650 1650);
DISPLAY 0.489362 (-9650 1650);
PAINT SKYBLUE (-9650 1650);
FORCEPROP 0 LAST $SEC 1
J 0
(-9650 1675);
DISPLAY 0.680851 (-9650 1675);
PAINT MONO (-9650 1675);
DISPLAY INVISIBLE (-9650 1675);
FORCEPROP 0 LAST CDS_SEC 1
J 0
(-9650 1675);
DISPLAY 1.021277 (-9650 1675);
DISPLAY INVISIBLE (-9650 1675);
FORCEPROP 1 LASTPIN (-9700 1650) $PN 1
J 0
(-9690 1630);
DISPLAY 0.489362 (-9690 1630);
PAINT MONO (-9690 1630);
FORCEPROP 1 LASTPIN (-9700 1450) $PN 2
J 0
(-9690 1430);
DISPLAY 0.489362 (-9690 1430);
PAINT MONO (-9690 1430);
FORCEPROP 1 LAST PART_NUMBER TMP_QCH21006JB10
J 0
(-9650 1350);
DISPLAY 0.489362 (-9650 1350);
PAINT SKYBLUE (-9650 1350);
FORCEPROP 1 LAST MATERIAL X7R
J 0
(-9650 1450);
DISPLAY 0.489362 (-9650 1450);
PAINT SKYBLUE (-9650 1450);
FORCEPROP 1 LAST TOLERANCE 5%
J 0
(-9650 1500);
DISPLAY 0.489362 (-9650 1500);
PAINT SKYBLUE (-9650 1500);
FORCEPROP 1 LAST VALUE 1000PF
J 0
(-9650 1600);
DISPLAY 0.489362 (-9650 1600);
PAINT SKYBLUE (-9650 1600);
FORCEPROP 1 LAST VOLTAGE 50V
J 0
(-9650 1550);
DISPLAY 0.489362 (-9650 1550);
PAINT SKYBLUE (-9650 1550);
FORCEPROP 1 LAST PACK_TYPE 0402
J 0
(-9650 1400);
DISPLAY 0.489362 (-9650 1400);
PAINT SKYBLUE (-9650 1400);
FORCEPROP 2 LAST CDS_LIB pure_quanta
J 0
(-9700 1550);
DISPLAY INVISIBLE (-9700 1550);
FORCEPROP 1 LAST PATH I397
J 0
(-9650 1700);
DISPLAY 0.978723 (-9650 1700);
PAINT WHITE (-9650 1700);
DISPLAY INVISIBLE (-9650 1700);
FORCEADD UNIVERSAL_GND..1
(-9700 1300);
FORCEPROP 3 LASTPIN (-9700 1350) SIG_NAME GND\g
J 0
(-9690 1360);
DISPLAY 0.659574 (-9690 1360);
PAINT MONO (-9690 1360);
DISPLAY INVISIBLE (-9690 1360);
FORCEPROP 2 LAST CDS_LIB pure_quanta_power
J 0
(-9700 1300);
DISPLAY INVISIBLE (-9700 1300);
FORCEPROP 1 LAST PATH I398
J 0
(-9625 1300);
DISPLAY 0.872340 (-9625 1300);
PAINT AQUA (-9625 1300);
DISPLAY INVISIBLE (-9625 1300);
FORCEPROP 1 LAST HDL_POWER GND
J 1
(-9675 1225);
DISPLAY 0.872340 (-9675 1225);
PAINT GREEN (-9675 1225);
DISPLAY INVISIBLE (-9675 1225);
FORCEADD VCC_CORE..1
(-8925 1075);
FORCEPROP 3 LASTPIN (-8925 1025) SIG_NAME P5V_STBY\g
J 0
(-8915 1035);
DISPLAY 0.659574 (-8915 1035);
PAINT MONO (-8915 1035);
DISPLAY INVISIBLE (-8915 1035);
FORCEPROP 1 LAST HDL_POWER P5V_STBY
J 1
(-8925 1125);
DISPLAY 0.489362 (-8925 1125);
PAINT GREEN (-8925 1125);
FORCEPROP 2 LAST CDS_LIB pure_quanta_power
J 0
(-8925 1075);
DISPLAY INVISIBLE (-8925 1075);
FORCEPROP 1 LAST PATH I399
J 0
(-8875 1100);
DISPLAY 0.872340 (-8875 1100);
PAINT AQUA (-8875 1100);
DISPLAY INVISIBLE (-8875 1100);
FORCEADD Q_CAP..1
(-4350 1575);
FORCEPROP 1 LAST LOCATION PC77
J 0
(-4300 1675);
DISPLAY 0.489362 (-4300 1675);
PAINT SKYBLUE (-4300 1675);
FORCEPROP 0 LAST $SEC 1
J 0
(-4300 1700);
DISPLAY 0.680851 (-4300 1700);
PAINT MONO (-4300 1700);
DISPLAY INVISIBLE (-4300 1700);
FORCEPROP 0 LAST CDS_SEC 1
J 0
(-4300 1700);
DISPLAY 1.021277 (-4300 1700);
DISPLAY INVISIBLE (-4300 1700);
FORCEPROP 1 LASTPIN (-4350 1675) $PN 1
J 0
(-4340 1655);
DISPLAY 0.489362 (-4340 1655);
PAINT MONO (-4340 1655);
FORCEPROP 1 LASTPIN (-4350 1475) $PN 2
J 0
(-4340 1455);
DISPLAY 0.489362 (-4340 1455);
PAINT MONO (-4340 1455);
FORCEPROP 1 LAST MATERIAL X7R
J 0
(-4300 1475);
DISPLAY 0.489362 (-4300 1475);
PAINT SKYBLUE (-4300 1475);
FORCEPROP 1 LAST TOLERANCE 10%
J 0
(-4300 1525);
DISPLAY 0.489362 (-4300 1525);
PAINT SKYBLUE (-4300 1525);
FORCEPROP 1 LAST VALUE 470PF
J 0
(-4300 1625);
DISPLAY 0.489362 (-4300 1625);
PAINT SKYBLUE (-4300 1625);
FORCEPROP 1 LAST PART_NUMBER TMP_QCH14706KB18
J 0
(-4300 1350);
DISPLAY 0.489362 (-4300 1350);
PAINT SKYBLUE (-4300 1350);
FORCEPROP 1 LAST VOLTAGE 50V
J 0
(-4300 1575);
DISPLAY 0.489362 (-4300 1575);
PAINT SKYBLUE (-4300 1575);
FORCEPROP 1 LAST PACK_TYPE 0402
J 0
(-4300 1425);
DISPLAY 0.489362 (-4300 1425);
PAINT SKYBLUE (-4300 1425);
FORCEPROP 2 LAST CDS_LIB pure_quanta
J 0
(-4350 1575);
DISPLAY INVISIBLE (-4350 1575);
FORCEPROP 1 LAST PATH I400
J 0
(-4300 1725);
DISPLAY 0.978723 (-4300 1725);
PAINT WHITE (-4300 1725);
DISPLAY INVISIBLE (-4300 1725);
FORCEADD UNIVERSAL_GND..1
(-4350 1325);
FORCEPROP 3 LASTPIN (-4350 1375) SIG_NAME GND\g
J 0
(-4340 1385);
DISPLAY 0.659574 (-4340 1385);
PAINT MONO (-4340 1385);
DISPLAY INVISIBLE (-4340 1385);
FORCEPROP 2 LAST CDS_LIB pure_quanta_power
J 0
(-4350 1325);
DISPLAY INVISIBLE (-4350 1325);
FORCEPROP 1 LAST PATH I401
J 0
(-4275 1325);
DISPLAY 0.872340 (-4275 1325);
PAINT AQUA (-4275 1325);
DISPLAY INVISIBLE (-4275 1325);
FORCEPROP 1 LAST HDL_POWER GND
J 1
(-4325 1250);
DISPLAY 0.872340 (-4325 1250);
PAINT GREEN (-4325 1250);
DISPLAY INVISIBLE (-4325 1250);
FORCEADD OFFPAGE..4
(-3750 1775);
FORCEPROP 2 LAST $XR1 182 
J 0
(-3444 1775);
DISPLAY 0.638298 (-3444 1775);
PAINT MONO (-3444 1775);
FORCEPROP 2 LAST $XR0 181 
J 0
(-3564 1775);
DISPLAY 0.638298 (-3564 1775);
PAINT MONO (-3564 1775);
FORCEPROP 2 LAST PATH I404
J 0
(-3575 1850);
DISPLAY 1.021277 (-3575 1850);
DISPLAY INVISIBLE (-3575 1850);
FORCEPROP 1 LAST COMMENT_BODY TRUE
J 0
(-3775 1675);
DISPLAY 0.872340 (-3775 1675);
PAINT GREEN (-3775 1675);
DISPLAY INVISIBLE (-3775 1675);
FORCEPROP 1 LAST OFFPAGE TRUE
J 0
(-3425 1650);
DISPLAY 0.872340 (-3425 1650);
PAINT GREEN (-3425 1650);
DISPLAY INVISIBLE (-3425 1650);
FORCEPROP 2 LAST CDS_LIB standard
J 0
(-3750 1775);
DISPLAY INVISIBLE (-3750 1775);
FORCEADD Q_RES..2
(-9350 6250);
FORCEPROP 1 LAST LOCATION PR48
J 0
(-9305 6375);
DISPLAY 0.489362 (-9305 6375);
PAINT SKYBLUE (-9305 6375);
FORCEPROP 0 LAST $SEC 1
J 0
(-9300 6400);
DISPLAY 0.680851 (-9300 6400);
PAINT MONO (-9300 6400);
DISPLAY INVISIBLE (-9300 6400);
FORCEPROP 0 LAST CDS_SEC 1
J 0
(-9300 6400);
DISPLAY 1.021277 (-9300 6400);
DISPLAY INVISIBLE (-9300 6400);
FORCEPROP 1 LASTPIN (-9350 6350) $PN 1
J 0
(-9345 6312);
DISPLAY 0.489362 (-9345 6312);
PAINT MONO (-9345 6312);
FORCEPROP 1 LASTPIN (-9350 6150) $PN 2
J 0
(-9345 6160);
DISPLAY 0.489362 (-9345 6160);
PAINT MONO (-9345 6160);
FORCEPROP 1 LAST WATTAGE 1/16W
J 0
(-9325 6175);
DISPLAY 0.489362 (-9325 6175);
PAINT SKYBLUE (-9325 6175);
FORCEPROP 1 LAST MATERIAL EMPTY
J 0
(-9325 6125);
DISPLAY 0.489362 (-9325 6125);
PAINT RED (-9325 6125);
FORCEPROP 1 LAST TOLERANCE 1%
J 0
(-9320 6225);
DISPLAY 0.489362 (-9320 6225);
PAINT SKYBLUE (-9320 6225);
FORCEPROP 1 LAST VALUE 1K
J 0
(-9320 6275);
DISPLAY 0.489362 (-9320 6275);
PAINT SKYBLUE (-9320 6275);
FORCEPROP 1 LAST PART_NUMBER TMP_QCS21002FB24
J 0
(-9325 6075);
DISPLAY 0.489362 (-9325 6075);
PAINT SKYBLUE (-9325 6075);
FORCEPROP 1 LAST PACK_TYPE 0402LF
J 0
(-9325 6025);
DISPLAY 0.489362 (-9325 6025);
PAINT SKYBLUE (-9325 6025);
FORCEPROP 2 LAST CDS_LIB pure_quanta
J 0
(-9350 6250);
DISPLAY INVISIBLE (-9350 6250);
FORCEPROP 1 LAST PATH I408
J 0
(-9300 6425);
DISPLAY 0.978723 (-9300 6425);
PAINT WHITE (-9300 6425);
DISPLAY INVISIBLE (-9300 6425);
FORCEADD Q_RES..2
(-10150 6250);
FORCEPROP 1 LAST LOCATION PR41
J 0
(-10105 6375);
DISPLAY 0.489362 (-10105 6375);
PAINT SKYBLUE (-10105 6375);
FORCEPROP 0 LAST $SEC 1
J 0
(-10100 6400);
DISPLAY 0.680851 (-10100 6400);
PAINT MONO (-10100 6400);
DISPLAY INVISIBLE (-10100 6400);
FORCEPROP 0 LAST CDS_SEC 1
J 0
(-10100 6400);
DISPLAY 1.021277 (-10100 6400);
DISPLAY INVISIBLE (-10100 6400);
FORCEPROP 1 LASTPIN (-10150 6350) $PN 1
J 0
(-10145 6312);
DISPLAY 0.489362 (-10145 6312);
PAINT MONO (-10145 6312);
FORCEPROP 1 LASTPIN (-10150 6150) $PN 2
J 0
(-10145 6160);
DISPLAY 0.489362 (-10145 6160);
PAINT MONO (-10145 6160);
FORCEPROP 1 LAST WATTAGE 1/16W
J 0
(-10125 6175);
DISPLAY 0.489362 (-10125 6175);
PAINT SKYBLUE (-10125 6175);
FORCEPROP 1 LAST MATERIAL EMPTY
J 0
(-10125 6125);
DISPLAY 0.489362 (-10125 6125);
PAINT RED (-10125 6125);
FORCEPROP 1 LAST TOLERANCE 1%
J 0
(-10120 6225);
DISPLAY 0.489362 (-10120 6225);
PAINT SKYBLUE (-10120 6225);
FORCEPROP 1 LAST VALUE 1K
J 0
(-10120 6275);
DISPLAY 0.489362 (-10120 6275);
PAINT SKYBLUE (-10120 6275);
FORCEPROP 1 LAST PACK_TYPE 0402LF
J 0
(-10125 6075);
DISPLAY 0.489362 (-10125 6075);
PAINT SKYBLUE (-10125 6075);
FORCEPROP 2 LAST CDS_LIB pure_quanta
J 0
(-10150 6250);
DISPLAY INVISIBLE (-10150 6250);
FORCEPROP 1 LAST PATH I409
J 0
(-10100 6425);
DISPLAY 0.978723 (-10100 6425);
PAINT WHITE (-10100 6425);
DISPLAY INVISIBLE (-10100 6425);
FORCEPROP 1 LAST PART_NUMBER TMP_QCS21002FB24
J 0
(-10125 6075);
DISPLAY 0.489362 (-10125 6075);
PAINT SKYBLUE (-10125 6075);
DISPLAY INVISIBLE (-10125 6075);
FORCEADD Q_RES..2
(-9800 6250);
FORCEPROP 1 LAST LOCATION PR43
J 0
(-9750 6375);
DISPLAY 0.489362 (-9750 6375);
PAINT SKYBLUE (-9750 6375);
FORCEPROP 0 LAST $SEC 1
J 0
(-9750 6400);
DISPLAY 0.680851 (-9750 6400);
PAINT MONO (-9750 6400);
DISPLAY INVISIBLE (-9750 6400);
FORCEPROP 0 LAST CDS_SEC 1
J 0
(-9750 6400);
DISPLAY 1.021277 (-9750 6400);
DISPLAY INVISIBLE (-9750 6400);
FORCEPROP 1 LASTPIN (-9800 6350) $PN 1
J 0
(-9795 6312);
DISPLAY 0.489362 (-9795 6312);
PAINT MONO (-9795 6312);
FORCEPROP 1 LASTPIN (-9800 6150) $PN 2
J 0
(-9795 6160);
DISPLAY 0.489362 (-9795 6160);
PAINT MONO (-9795 6160);
FORCEPROP 1 LAST WATTAGE 1/16W
J 0
(-9775 6175);
DISPLAY 0.489362 (-9775 6175);
PAINT SKYBLUE (-9775 6175);
FORCEPROP 1 LAST MATERIAL EMPTY
J 0
(-9775 6125);
DISPLAY 0.489362 (-9775 6125);
PAINT RED (-9775 6125);
FORCEPROP 1 LAST TOLERANCE 1%
J 0
(-9770 6225);
DISPLAY 0.489362 (-9770 6225);
PAINT SKYBLUE (-9770 6225);
FORCEPROP 1 LAST VALUE 1K
J 0
(-9770 6275);
DISPLAY 0.489362 (-9770 6275);
PAINT SKYBLUE (-9770 6275);
FORCEPROP 1 LAST PACK_TYPE 0402LF
J 0
(-9775 6075);
DISPLAY 0.489362 (-9775 6075);
PAINT SKYBLUE (-9775 6075);
FORCEPROP 2 LAST CDS_LIB pure_quanta
J 0
(-9800 6250);
DISPLAY INVISIBLE (-9800 6250);
FORCEPROP 1 LAST PATH I410
J 0
(-9750 6425);
DISPLAY 0.978723 (-9750 6425);
PAINT WHITE (-9750 6425);
DISPLAY INVISIBLE (-9750 6425);
FORCEPROP 1 LAST PART_NUMBER TMP_QCS21002FB24
J 0
(-9775 6075);
DISPLAY 0.489362 (-9775 6075);
PAINT SKYBLUE (-9775 6075);
DISPLAY INVISIBLE (-9775 6075);
FORCEADD Q_RES..2
(-9600 6250);
FORCEPROP 1 LAST LOCATION PR45
J 0
(-9555 6375);
DISPLAY 0.489362 (-9555 6375);
PAINT SKYBLUE (-9555 6375);
FORCEPROP 0 LAST $SEC 1
J 0
(-9550 6400);
DISPLAY 0.680851 (-9550 6400);
PAINT MONO (-9550 6400);
DISPLAY INVISIBLE (-9550 6400);
FORCEPROP 0 LAST CDS_SEC 1
J 0
(-9550 6400);
DISPLAY 1.021277 (-9550 6400);
DISPLAY INVISIBLE (-9550 6400);
FORCEPROP 1 LASTPIN (-9600 6350) $PN 1
J 0
(-9595 6312);
DISPLAY 0.489362 (-9595 6312);
PAINT MONO (-9595 6312);
FORCEPROP 1 LASTPIN (-9600 6150) $PN 2
J 0
(-9595 6160);
DISPLAY 0.489362 (-9595 6160);
PAINT MONO (-9595 6160);
FORCEPROP 1 LAST WATTAGE 1/16W
J 0
(-9575 6175);
DISPLAY 0.489362 (-9575 6175);
PAINT SKYBLUE (-9575 6175);
FORCEPROP 1 LAST MATERIAL EMPTY
J 0
(-9575 6125);
DISPLAY 0.489362 (-9575 6125);
PAINT RED (-9575 6125);
FORCEPROP 1 LAST TOLERANCE 1%
J 0
(-9570 6225);
DISPLAY 0.489362 (-9570 6225);
PAINT SKYBLUE (-9570 6225);
FORCEPROP 1 LAST VALUE 1K
J 0
(-9570 6275);
DISPLAY 0.489362 (-9570 6275);
PAINT SKYBLUE (-9570 6275);
FORCEPROP 1 LAST PACK_TYPE 0402LF
J 0
(-9575 6075);
DISPLAY 0.489362 (-9575 6075);
PAINT SKYBLUE (-9575 6075);
FORCEPROP 2 LAST CDS_LIB pure_quanta
J 0
(-9600 6250);
DISPLAY INVISIBLE (-9600 6250);
FORCEPROP 1 LAST PATH I411
J 0
(-9550 6425);
DISPLAY 0.978723 (-9550 6425);
PAINT WHITE (-9550 6425);
DISPLAY INVISIBLE (-9550 6425);
FORCEPROP 1 LAST PART_NUMBER TMP_QCS21002FB24
J 0
(-9575 6075);
DISPLAY 0.489362 (-9575 6075);
PAINT SKYBLUE (-9575 6075);
DISPLAY INVISIBLE (-9575 6075);
FORCEADD Q_RES..2
(-10025 5275);
FORCEPROP 1 LAST LOCATION PR42
J 0
(-9980 5400);
DISPLAY 0.489362 (-9980 5400);
PAINT SKYBLUE (-9980 5400);
FORCEPROP 0 LAST $SEC 1
J 0
(-9975 5425);
DISPLAY 0.680851 (-9975 5425);
PAINT MONO (-9975 5425);
DISPLAY INVISIBLE (-9975 5425);
FORCEPROP 0 LAST CDS_SEC 1
J 0
(-9975 5425);
DISPLAY 1.021277 (-9975 5425);
DISPLAY INVISIBLE (-9975 5425);
FORCEPROP 1 LASTPIN (-10025 5375) $PN 1
J 0
(-10020 5337);
DISPLAY 0.489362 (-10020 5337);
PAINT MONO (-10020 5337);
FORCEPROP 1 LASTPIN (-10025 5175) $PN 2
J 0
(-10020 5185);
DISPLAY 0.489362 (-10020 5185);
PAINT MONO (-10020 5185);
FORCEPROP 1 LAST WATTAGE 1/16W
J 0
(-10000 5200);
DISPLAY 0.489362 (-10000 5200);
PAINT SKYBLUE (-10000 5200);
FORCEPROP 1 LAST MATERIAL EMPTY
J 0
(-10000 5150);
DISPLAY 0.489362 (-10000 5150);
PAINT RED (-10000 5150);
FORCEPROP 1 LAST TOLERANCE 1%
J 0
(-9995 5250);
DISPLAY 0.489362 (-9995 5250);
PAINT SKYBLUE (-9995 5250);
FORCEPROP 1 LAST VALUE 1K
J 0
(-9995 5300);
DISPLAY 0.489362 (-9995 5300);
PAINT SKYBLUE (-9995 5300);
FORCEPROP 1 LAST PACK_TYPE 0402LF
J 0
(-10000 5100);
DISPLAY 0.489362 (-10000 5100);
PAINT SKYBLUE (-10000 5100);
FORCEPROP 2 LAST CDS_LIB pure_quanta
J 0
(-10025 5275);
DISPLAY INVISIBLE (-10025 5275);
FORCEPROP 1 LAST PATH I414
J 0
(-9975 5450);
DISPLAY 0.978723 (-9975 5450);
PAINT WHITE (-9975 5450);
DISPLAY INVISIBLE (-9975 5450);
FORCEPROP 1 LAST PART_NUMBER TMP_QCS21002FB24
J 0
(-10000 5100);
DISPLAY 0.489362 (-10000 5100);
PAINT SKYBLUE (-10000 5100);
DISPLAY INVISIBLE (-10000 5100);
FORCEADD Q_RES..2
(-10250 5275);
FORCEPROP 1 LAST LOCATION PR40
J 0
(-10205 5400);
DISPLAY 0.489362 (-10205 5400);
PAINT SKYBLUE (-10205 5400);
FORCEPROP 0 LAST $SEC 1
J 0
(-10200 5425);
DISPLAY 0.680851 (-10200 5425);
PAINT MONO (-10200 5425);
DISPLAY INVISIBLE (-10200 5425);
FORCEPROP 0 LAST CDS_SEC 1
J 0
(-10200 5425);
DISPLAY 1.021277 (-10200 5425);
DISPLAY INVISIBLE (-10200 5425);
FORCEPROP 1 LASTPIN (-10250 5375) $PN 1
J 0
(-10245 5337);
DISPLAY 0.489362 (-10245 5337);
PAINT MONO (-10245 5337);
FORCEPROP 1 LASTPIN (-10250 5175) $PN 2
J 0
(-10245 5185);
DISPLAY 0.489362 (-10245 5185);
PAINT MONO (-10245 5185);
FORCEPROP 1 LAST WATTAGE 1/16W
J 0
(-10225 5200);
DISPLAY 0.489362 (-10225 5200);
PAINT SKYBLUE (-10225 5200);
FORCEPROP 1 LAST MATERIAL CHIP
J 0
(-10225 5150);
DISPLAY 0.489362 (-10225 5150);
PAINT SKYBLUE (-10225 5150);
FORCEPROP 1 LAST TOLERANCE 5%
J 0
(-10220 5250);
DISPLAY 0.489362 (-10220 5250);
PAINT SKYBLUE (-10220 5250);
FORCEPROP 1 LAST VALUE 1K
J 0
(-10220 5300);
DISPLAY 0.489362 (-10220 5300);
PAINT SKYBLUE (-10220 5300);
FORCEPROP 1 LAST PACK_TYPE 0402LF
J 0
(-10225 5100);
DISPLAY 0.489362 (-10225 5100);
PAINT SKYBLUE (-10225 5100);
FORCEPROP 2 LAST CDS_LIB pure_quanta
J 0
(-10250 5275);
DISPLAY INVISIBLE (-10250 5275);
FORCEPROP 1 LAST PATH I415
J 0
(-10200 5450);
DISPLAY 0.978723 (-10200 5450);
PAINT WHITE (-10200 5450);
DISPLAY INVISIBLE (-10200 5450);
FORCEPROP 1 LAST PART_NUMBER TMP_QCS21002JB34
J 0
(-10225 5100);
DISPLAY 0.489362 (-10225 5100);
PAINT SKYBLUE (-10225 5100);
DISPLAY INVISIBLE (-10225 5100);
FORCEADD UNIVERSAL_GND..1
(-10250 4825);
FORCEPROP 3 LASTPIN (-10250 4875) SIG_NAME GND\g
J 0
(-10240 4885);
DISPLAY 0.659574 (-10240 4885);
PAINT MONO (-10240 4885);
DISPLAY INVISIBLE (-10240 4885);
FORCEPROP 2 LAST CDS_LIB pure_quanta_power
J 0
(-10250 4825);
DISPLAY INVISIBLE (-10250 4825);
FORCEPROP 1 LAST PATH I416
J 0
(-10175 4825);
DISPLAY 0.872340 (-10175 4825);
PAINT AQUA (-10175 4825);
DISPLAY INVISIBLE (-10175 4825);
FORCEPROP 1 LAST HDL_POWER GND
J 1
(-10225 4750);
DISPLAY 0.872340 (-10225 4750);
PAINT GREEN (-10225 4750);
DISPLAY INVISIBLE (-10225 4750);
FORCEADD VCC_CORE..1
(-10150 6600);
FORCEPROP 3 LASTPIN (-10150 6550) SIG_NAME PVDD18_S5_P0\g
J 0
(-10140 6560);
DISPLAY 0.659574 (-10140 6560);
PAINT MONO (-10140 6560);
DISPLAY INVISIBLE (-10140 6560);
FORCEPROP 1 LAST HDL_POWER PVDD18_S5_P0
J 1
(-10150 6650);
DISPLAY 0.489362 (-10150 6650);
PAINT GREEN (-10150 6650);
FORCEPROP 2 LAST CDS_LIB pure_quanta_power
J 0
(-10150 6600);
DISPLAY INVISIBLE (-10150 6600);
FORCEPROP 1 LAST PATH I417
J 0
(-10100 6625);
DISPLAY 0.872340 (-10100 6625);
PAINT AQUA (-10100 6625);
DISPLAY INVISIBLE (-10100 6625);
FORCEADD UNIVERSAL_GND..1
(-4350 6000);
FORCEPROP 3 LASTPIN (-4350 6050) SIG_NAME GND\g
J 0
(-4340 6060);
DISPLAY 0.659574 (-4340 6060);
PAINT MONO (-4340 6060);
DISPLAY INVISIBLE (-4340 6060);
FORCEPROP 2 LAST CDS_LIB pure_quanta_power
J 0
(-4350 6000);
DISPLAY INVISIBLE (-4350 6000);
FORCEPROP 1 LAST PATH I418
J 0
(-4275 6000);
DISPLAY 0.872340 (-4275 6000);
PAINT AQUA (-4275 6000);
DISPLAY INVISIBLE (-4275 6000);
FORCEPROP 1 LAST HDL_POWER GND
J 1
(-4325 5925);
DISPLAY 0.872340 (-4325 5925);
PAINT GREEN (-4325 5925);
DISPLAY INVISIBLE (-4325 5925);
FORCEADD UNIVERSAL_GND..1
(-4350 5525);
FORCEPROP 3 LASTPIN (-4350 5575) SIG_NAME GND\g
J 0
(-4340 5585);
DISPLAY 0.659574 (-4340 5585);
PAINT MONO (-4340 5585);
DISPLAY INVISIBLE (-4340 5585);
FORCEPROP 2 LAST CDS_LIB pure_quanta_power
J 0
(-4350 5525);
DISPLAY INVISIBLE (-4350 5525);
FORCEPROP 1 LAST PATH I419
J 0
(-4275 5525);
DISPLAY 0.872340 (-4275 5525);
PAINT AQUA (-4275 5525);
DISPLAY INVISIBLE (-4275 5525);
FORCEPROP 1 LAST HDL_POWER GND
J 1
(-4325 5450);
DISPLAY 0.872340 (-4325 5450);
PAINT GREEN (-4325 5450);
DISPLAY INVISIBLE (-4325 5450);
FORCEADD VCC_CORE..1
(-7925 2800);
FORCEPROP 3 LASTPIN (-7925 2750) SIG_NAME PVDD18_S5_P0\g
J 0
(-7915 2760);
DISPLAY 0.659574 (-7915 2760);
PAINT MONO (-7915 2760);
DISPLAY INVISIBLE (-7915 2760);
FORCEPROP 1 LAST HDL_POWER PVDD18_S5_P0
J 1
(-7925 2850);
DISPLAY 0.489362 (-7925 2850);
PAINT GREEN (-7925 2850);
FORCEPROP 2 LAST CDS_LIB pure_quanta_power
J 0
(-7925 2800);
DISPLAY INVISIBLE (-7925 2800);
FORCEPROP 1 LAST PATH I423
J 0
(-7875 2825);
DISPLAY 0.872340 (-7875 2825);
PAINT AQUA (-7875 2825);
DISPLAY INVISIBLE (-7875 2825);
FORCEADD MOSFET_PCH_GDS_ESD_PROTECTED..1
R 6
(-8575 2150);
FORCEPROP 1 LAST LOCATION PQ10
J 0
(-8400 2000);
DISPLAY 0.489362 (-8400 2000);
PAINT SKYBLUE (-8400 2000);
FORCEPROP 0 LAST $SEC 1
J 0
(-8400 2175);
DISPLAY 0.680851 (-8400 2175);
PAINT MONO (-8400 2175);
DISPLAY INVISIBLE (-8400 2175);
FORCEPROP 0 LAST CDS_SEC 1
J 0
(-8400 2175);
DISPLAY 1.021277 (-8400 2175);
DISPLAY INVISIBLE (-8400 2175);
FORCEPROP 0 LASTPIN (-8550 1850) $PN D
R 1
J 2
(-8560 1840);
DISPLAY 0.489362 (-8560 1840);
PAINT MONO (-8560 1840);
FORCEPROP 0 LASTPIN (-8850 2150) $PN G
J 2
(-8860 2160);
DISPLAY 0.489362 (-8860 2160);
PAINT MONO (-8860 2160);
FORCEPROP 0 LASTPIN (-8550 2450) $PN S
R 1
J 0
(-8560 2460);
DISPLAY 0.489362 (-8560 2460);
PAINT MONO (-8560 2460);
FORCEPROP 1 LAST MATERIAL IC
J 0
(-8400 2152);
DISPLAY 0.489362 (-8400 2152);
PAINT SKYBLUE (-8400 2152);
FORCEPROP 2 LAST VALUE PJA3415AE
J 0
(-8400 2102);
DISPLAY 0.489362 (-8400 2102);
PAINT SKYBLUE (-8400 2102);
FORCEPROP 1 LAST PART_NUMBER BAM34150008
J 0
(-8400 2052);
DISPLAY 0.489362 (-8400 2052);
PAINT SKYBLUE (-8400 2052);
FORCEPROP 2 LAST PART_TYPE SMLF
J 0
(-8425 1977);
DISPLAY 1.021277 (-8425 1977);
DISPLAY INVISIBLE (-8425 1977);
FORCEPROP 2 LAST CDS_LIB pure_quanta
J 0
(-8575 2150);
DISPLAY INVISIBLE (-8575 2150);
FORCEPROP 1 LAST NEEDS_NO_SIZE TRUE
J 0
(-8575 2116);
DISPLAY 0.723404 (-8575 2116);
PAINT GREEN (-8575 2116);
DISPLAY INVISIBLE (-8575 2116);
FORCEPROP 1 LAST CDS_LMAN_SYM_OUTLINE -125,150,125,-150
J 0
(-8575 2150);
DISPLAY 0.468085 (-8575 2150);
PAINT GREEN (-8575 2150);
DISPLAY INVISIBLE (-8575 2150);
FORCEPROP 1 LAST PATH I424
J 0
(-8575 2150);
DISPLAY 0.723404 (-8575 2150);
PAINT GREEN (-8575 2150);
DISPLAY INVISIBLE (-8575 2150);
FORCEADD UNIVERSAL_GND..1
(-4675 5525);
FORCEPROP 3 LASTPIN (-4675 5575) SIG_NAME GND\g
J 0
(-4665 5585);
DISPLAY 0.659574 (-4665 5585);
PAINT MONO (-4665 5585);
DISPLAY INVISIBLE (-4665 5585);
FORCEPROP 2 LAST CDS_LIB pure_quanta_power
J 0
(-4675 5525);
DISPLAY INVISIBLE (-4675 5525);
FORCEPROP 1 LAST PATH I425
J 0
(-4600 5525);
DISPLAY 0.872340 (-4600 5525);
PAINT AQUA (-4600 5525);
DISPLAY INVISIBLE (-4600 5525);
FORCEPROP 1 LAST HDL_POWER GND
J 1
(-4650 5450);
DISPLAY 0.872340 (-4650 5450);
PAINT GREEN (-4650 5450);
DISPLAY INVISIBLE (-4650 5450);
FORCEADD Q_CAP..1
(-4675 5750);
FORCEPROP 1 LAST LOCATION PC15
J 0
(-4625 5850);
DISPLAY 0.489362 (-4625 5850);
PAINT SKYBLUE (-4625 5850);
FORCEPROP 0 LAST $SEC 1
J 0
(-4625 5875);
DISPLAY 0.680851 (-4625 5875);
PAINT MONO (-4625 5875);
DISPLAY INVISIBLE (-4625 5875);
FORCEPROP 0 LAST CDS_SEC 1
J 0
(-4625 5875);
DISPLAY 1.021277 (-4625 5875);
DISPLAY INVISIBLE (-4625 5875);
FORCEPROP 1 LASTPIN (-4675 5850) $PN 1
J 0
(-4665 5830);
DISPLAY 0.489362 (-4665 5830);
PAINT MONO (-4665 5830);
FORCEPROP 1 LASTPIN (-4675 5650) $PN 2
J 0
(-4665 5630);
DISPLAY 0.489362 (-4665 5630);
PAINT MONO (-4665 5630);
FORCEPROP 1 LAST TOLERANCE 10%
J 0
(-4625 5700);
DISPLAY 0.489362 (-4625 5700);
PAINT SKYBLUE (-4625 5700);
FORCEPROP 1 LAST VALUE 0.1UF
J 0
(-4625 5800);
DISPLAY 0.489362 (-4625 5800);
PAINT SKYBLUE (-4625 5800);
FORCEPROP 1 LAST MATERIAL X7R
J 0
(-4625 5650);
DISPLAY 0.489362 (-4625 5650);
PAINT SKYBLUE (-4625 5650);
FORCEPROP 1 LAST PART_NUMBER CH4104K1B00
J 0
(-4625 5600);
DISPLAY 0.489362 (-4625 5600);
PAINT SKYBLUE (-4625 5600);
FORCEPROP 1 LAST VOLTAGE 25V
J 0
(-4625 5750);
DISPLAY 0.489362 (-4625 5750);
PAINT SKYBLUE (-4625 5750);
FORCEPROP 1 LAST PACK_TYPE 0402
J 0
(-4625 5550);
DISPLAY 0.489362 (-4625 5550);
PAINT SKYBLUE (-4625 5550);
FORCEPROP 2 LAST CDS_LIB pure_quanta
J 0
(-4675 5750);
DISPLAY INVISIBLE (-4675 5750);
FORCEPROP 1 LAST PATH I426
J 0
(-4625 5900);
DISPLAY 0.978723 (-4625 5900);
PAINT WHITE (-4625 5900);
DISPLAY INVISIBLE (-4625 5900);
FORCEADD UNIVERSAL_GND..1
(-4675 6000);
FORCEPROP 3 LASTPIN (-4675 6050) SIG_NAME GND\g
J 0
(-4665 6060);
DISPLAY 0.659574 (-4665 6060);
PAINT MONO (-4665 6060);
DISPLAY INVISIBLE (-4665 6060);
FORCEPROP 2 LAST CDS_LIB pure_quanta_power
J 0
(-4675 6000);
DISPLAY INVISIBLE (-4675 6000);
FORCEPROP 1 LAST PATH I427
J 0
(-4600 6000);
DISPLAY 0.872340 (-4600 6000);
PAINT AQUA (-4600 6000);
DISPLAY INVISIBLE (-4600 6000);
FORCEPROP 1 LAST HDL_POWER GND
J 1
(-4650 5925);
DISPLAY 0.872340 (-4650 5925);
PAINT GREEN (-4650 5925);
DISPLAY INVISIBLE (-4650 5925);
FORCEADD Q_CAP..1
(-4675 6225);
FORCEPROP 1 LAST LOCATION PC14
J 0
(-4625 6325);
DISPLAY 0.489362 (-4625 6325);
PAINT SKYBLUE (-4625 6325);
FORCEPROP 0 LAST $SEC 1
J 0
(-4625 6350);
DISPLAY 0.680851 (-4625 6350);
PAINT MONO (-4625 6350);
DISPLAY INVISIBLE (-4625 6350);
FORCEPROP 0 LAST CDS_SEC 1
J 0
(-4625 6350);
DISPLAY 1.021277 (-4625 6350);
DISPLAY INVISIBLE (-4625 6350);
FORCEPROP 1 LASTPIN (-4675 6325) $PN 1
J 0
(-4665 6305);
DISPLAY 0.489362 (-4665 6305);
PAINT MONO (-4665 6305);
FORCEPROP 1 LASTPIN (-4675 6125) $PN 2
J 0
(-4665 6105);
DISPLAY 0.489362 (-4665 6105);
PAINT MONO (-4665 6105);
FORCEPROP 1 LAST MATERIAL X7R
J 0
(-4625 6125);
DISPLAY 0.489362 (-4625 6125);
PAINT SKYBLUE (-4625 6125);
FORCEPROP 1 LAST TOLERANCE 10%
J 0
(-4625 6175);
DISPLAY 0.489362 (-4625 6175);
PAINT SKYBLUE (-4625 6175);
FORCEPROP 1 LAST VALUE 0.1UF
J 0
(-4625 6275);
DISPLAY 0.489362 (-4625 6275);
PAINT SKYBLUE (-4625 6275);
FORCEPROP 1 LAST PART_NUMBER CH4104K1B00
J 0
(-4625 6075);
DISPLAY 0.489362 (-4625 6075);
PAINT SKYBLUE (-4625 6075);
FORCEPROP 1 LAST VOLTAGE 25V
J 0
(-4625 6225);
DISPLAY 0.489362 (-4625 6225);
PAINT SKYBLUE (-4625 6225);
FORCEPROP 1 LAST PACK_TYPE 0402
J 0
(-4625 6025);
DISPLAY 0.489362 (-4625 6025);
PAINT SKYBLUE (-4625 6025);
FORCEPROP 2 LAST CDS_LIB pure_quanta
J 0
(-4675 6225);
DISPLAY INVISIBLE (-4675 6225);
FORCEPROP 1 LAST PATH I428
J 0
(-4625 6375);
DISPLAY 0.978723 (-4625 6375);
PAINT WHITE (-4625 6375);
DISPLAY INVISIBLE (-4625 6375);
FORCEADD OFFPAGE..1
(-10225 5775);
FORCEPROP 2 LAST $XR0 27 
J 0
(-10446 5775);
DISPLAY 0.638298 (-10446 5775);
PAINT MONO (-10446 5775);
FORCEPROP 2 LAST PATH I437
J 0
(-10175 5850);
DISPLAY 1.021277 (-10175 5850);
DISPLAY INVISIBLE (-10175 5850);
FORCEPROP 1 LAST COMMENT_BODY TRUE
J 0
(-10100 5675);
DISPLAY 0.872340 (-10100 5675);
PAINT GREEN (-10100 5675);
DISPLAY INVISIBLE (-10100 5675);
FORCEPROP 1 LAST OFFPAGE TRUE
J 0
(-9900 5650);
DISPLAY 0.872340 (-9900 5650);
PAINT GREEN (-9900 5650);
DISPLAY INVISIBLE (-9900 5650);
FORCEPROP 2 LAST CDS_LIB standard
J 0
(-10225 5775);
DISPLAY INVISIBLE (-10225 5775);
FORCEADD OFFPAGE..1
(-10225 5925);
FORCEPROP 2 LAST $XR0 27 
J 0
(-10446 5925);
DISPLAY 0.638298 (-10446 5925);
PAINT MONO (-10446 5925);
FORCEPROP 2 LAST PATH I438
J 0
(-10175 6000);
DISPLAY 1.021277 (-10175 6000);
DISPLAY INVISIBLE (-10175 6000);
FORCEPROP 1 LAST COMMENT_BODY TRUE
J 0
(-10100 5825);
DISPLAY 0.872340 (-10100 5825);
PAINT GREEN (-10100 5825);
DISPLAY INVISIBLE (-10100 5825);
FORCEPROP 1 LAST OFFPAGE TRUE
J 0
(-9900 5800);
DISPLAY 0.872340 (-9900 5800);
PAINT GREEN (-9900 5800);
DISPLAY INVISIBLE (-9900 5800);
FORCEPROP 2 LAST CDS_LIB standard
J 0
(-10225 5925);
DISPLAY INVISIBLE (-10225 5925);
FORCEADD Q_CAP..1
(-9425 5275);
FORCEPROP 1 LAST LOCATION PC305
J 0
(-9325 5375);
DISPLAY 0.489362 (-9325 5375);
PAINT SKYBLUE (-9325 5375);
FORCEPROP 0 LAST $SEC 1
J 0
(-9375 5400);
DISPLAY 0.680851 (-9375 5400);
PAINT MONO (-9375 5400);
DISPLAY INVISIBLE (-9375 5400);
FORCEPROP 0 LAST CDS_SEC 1
J 0
(-9375 5400);
DISPLAY 1.021277 (-9375 5400);
DISPLAY INVISIBLE (-9375 5400);
FORCEPROP 1 LASTPIN (-9425 5375) $PN 1
J 0
(-9415 5355);
DISPLAY 0.489362 (-9415 5355);
PAINT MONO (-9415 5355);
FORCEPROP 1 LASTPIN (-9425 5175) $PN 2
J 0
(-9415 5155);
DISPLAY 0.489362 (-9415 5155);
PAINT MONO (-9415 5155);
FORCEPROP 1 LAST MATERIAL EMPTY
J 0
(-9325 5175);
DISPLAY 0.489362 (-9325 5175);
PAINT RED (-9325 5175);
FORCEPROP 1 LAST TOLERANCE 5%
J 0
(-9325 5225);
DISPLAY 0.489362 (-9325 5225);
PAINT SKYBLUE (-9325 5225);
FORCEPROP 1 LAST VALUE 10PF
J 0
(-9325 5325);
DISPLAY 0.489362 (-9325 5325);
PAINT SKYBLUE (-9325 5325);
FORCEPROP 1 LAST PART_NUMBER CH01006JB08
J 0
(-9325 5125);
DISPLAY 0.489362 (-9325 5125);
PAINT SKYBLUE (-9325 5125);
FORCEPROP 1 LAST VOLTAGE 50V
J 0
(-9325 5275);
DISPLAY 0.489362 (-9325 5275);
PAINT SKYBLUE (-9325 5275);
FORCEPROP 1 LAST PACK_TYPE 0402
J 0
(-9325 5075);
DISPLAY 0.489362 (-9325 5075);
PAINT SKYBLUE (-9325 5075);
FORCEPROP 2 LAST CDS_LIB pure_quanta
J 0
(-9425 5275);
DISPLAY INVISIBLE (-9425 5275);
FORCEPROP 1 LAST PATH I465
J 0
(-9375 5425);
DISPLAY 0.978723 (-9375 5425);
PAINT WHITE (-9375 5425);
DISPLAY INVISIBLE (-9375 5425);
FORCEADD Q_CAP..1
(-9675 5275);
FORCEPROP 1 LAST LOCATION PC304
J 0
(-9625 5375);
DISPLAY 0.489362 (-9625 5375);
PAINT SKYBLUE (-9625 5375);
FORCEPROP 0 LAST $SEC 1
J 0
(-9625 5400);
DISPLAY 0.680851 (-9625 5400);
PAINT MONO (-9625 5400);
DISPLAY INVISIBLE (-9625 5400);
FORCEPROP 0 LAST CDS_SEC 1
J 0
(-9625 5400);
DISPLAY 1.021277 (-9625 5400);
DISPLAY INVISIBLE (-9625 5400);
FORCEPROP 1 LASTPIN (-9675 5375) $PN 1
J 0
(-9665 5355);
DISPLAY 0.489362 (-9665 5355);
PAINT MONO (-9665 5355);
FORCEPROP 1 LASTPIN (-9675 5175) $PN 2
J 0
(-9665 5155);
DISPLAY 0.489362 (-9665 5155);
PAINT MONO (-9665 5155);
FORCEPROP 1 LAST MATERIAL EMPTY
J 0
(-9625 5175);
DISPLAY 0.489362 (-9625 5175);
PAINT RED (-9625 5175);
FORCEPROP 1 LAST TOLERANCE 5%
J 0
(-9625 5225);
DISPLAY 0.489362 (-9625 5225);
PAINT SKYBLUE (-9625 5225);
FORCEPROP 1 LAST VALUE 10PF
J 0
(-9625 5325);
DISPLAY 0.489362 (-9625 5325);
PAINT SKYBLUE (-9625 5325);
FORCEPROP 1 LAST PART_NUMBER CH01006JB08
J 0
(-9625 5125);
DISPLAY 0.489362 (-9625 5125);
PAINT SKYBLUE (-9625 5125);
FORCEPROP 1 LAST VOLTAGE 50V
J 0
(-9625 5275);
DISPLAY 0.489362 (-9625 5275);
PAINT SKYBLUE (-9625 5275);
FORCEPROP 1 LAST PACK_TYPE 0402
J 0
(-9625 5075);
DISPLAY 0.489362 (-9625 5075);
PAINT SKYBLUE (-9625 5075);
FORCEPROP 2 LAST CDS_LIB pure_quanta
J 0
(-9675 5275);
DISPLAY INVISIBLE (-9675 5275);
FORCEPROP 1 LAST PATH I466
J 0
(-9625 5425);
DISPLAY 0.978723 (-9625 5425);
PAINT WHITE (-9625 5425);
DISPLAY INVISIBLE (-9625 5425);
FORCEADD Q_CAP..1
(-9850 5275);
FORCEPROP 1 LAST LOCATION PC303
J 0
(-9800 5375);
DISPLAY 0.489362 (-9800 5375);
PAINT SKYBLUE (-9800 5375);
FORCEPROP 0 LAST $SEC 1
J 0
(-9800 5400);
DISPLAY 0.680851 (-9800 5400);
PAINT MONO (-9800 5400);
DISPLAY INVISIBLE (-9800 5400);
FORCEPROP 0 LAST CDS_SEC 1
J 0
(-9800 5400);
DISPLAY 1.021277 (-9800 5400);
DISPLAY INVISIBLE (-9800 5400);
FORCEPROP 1 LASTPIN (-9850 5375) $PN 1
J 0
(-9840 5355);
DISPLAY 0.489362 (-9840 5355);
PAINT MONO (-9840 5355);
FORCEPROP 1 LASTPIN (-9850 5175) $PN 2
J 0
(-9840 5155);
DISPLAY 0.489362 (-9840 5155);
PAINT MONO (-9840 5155);
FORCEPROP 1 LAST MATERIAL EMPTY
J 0
(-9800 5175);
DISPLAY 0.489362 (-9800 5175);
PAINT RED (-9800 5175);
FORCEPROP 1 LAST TOLERANCE 5%
J 0
(-9800 5225);
DISPLAY 0.489362 (-9800 5225);
PAINT SKYBLUE (-9800 5225);
FORCEPROP 1 LAST VALUE 10PF
J 0
(-9800 5325);
DISPLAY 0.489362 (-9800 5325);
PAINT SKYBLUE (-9800 5325);
FORCEPROP 1 LAST PART_NUMBER CH01006JB08
J 0
(-9800 5125);
DISPLAY 0.489362 (-9800 5125);
PAINT SKYBLUE (-9800 5125);
FORCEPROP 1 LAST VOLTAGE 50V
J 0
(-9800 5275);
DISPLAY 0.489362 (-9800 5275);
PAINT SKYBLUE (-9800 5275);
FORCEPROP 1 LAST PACK_TYPE 0402
J 0
(-9800 5075);
DISPLAY 0.489362 (-9800 5075);
PAINT SKYBLUE (-9800 5075);
FORCEPROP 2 LAST CDS_LIB pure_quanta
J 0
(-9850 5275);
DISPLAY INVISIBLE (-9850 5275);
FORCEPROP 1 LAST PATH I467
J 0
(-9800 5425);
DISPLAY 0.978723 (-9800 5425);
PAINT WHITE (-9800 5425);
DISPLAY INVISIBLE (-9800 5425);
FORCEADD OFFPAGE..2
(-3900 2075);
FORCEPROP 2 LAST $XR0 181 
J 0
(-3711 2075);
DISPLAY 0.638298 (-3711 2075);
PAINT MONO (-3711 2075);
FORCEPROP 1 LAST COMMENT_BODY TRUE
J 0
(-3945 1980);
DISPLAY 0.872340 (-3945 1980);
PAINT GREEN (-3945 1980);
DISPLAY INVISIBLE (-3945 1980);
FORCEPROP 1 LAST OFFPAGE TRUE
J 0
(-3575 1950);
DISPLAY 0.872340 (-3575 1950);
PAINT GREEN (-3575 1950);
DISPLAY INVISIBLE (-3575 1950);
FORCEPROP 2 LAST CDS_LIB standard
J 0
(-3900 2075);
DISPLAY INVISIBLE (-3900 2075);
FORCEPROP 2 LAST PATH I468
J 0
(-3700 2125);
DISPLAY 1.021277 (-3700 2125);
DISPLAY INVISIBLE (-3700 2125);
FORCEADD OFFPAGE..4
(-3900 1975);
FORCEPROP 2 LAST $XR0 181 
J 0
(-3714 1975);
DISPLAY 0.638298 (-3714 1975);
PAINT MONO (-3714 1975);
FORCEPROP 1 LAST COMMENT_BODY TRUE
J 0
(-3925 1875);
DISPLAY 0.872340 (-3925 1875);
PAINT GREEN (-3925 1875);
DISPLAY INVISIBLE (-3925 1875);
FORCEPROP 1 LAST OFFPAGE TRUE
J 0
(-3575 1850);
DISPLAY 0.872340 (-3575 1850);
PAINT GREEN (-3575 1850);
DISPLAY INVISIBLE (-3575 1850);
FORCEPROP 2 LAST CDS_LIB standard
J 0
(-3900 1975);
DISPLAY INVISIBLE (-3900 1975);
FORCEPROP 2 LAST PATH I469
J 0
(-3700 2025);
DISPLAY 1.021277 (-3700 2025);
DISPLAY INVISIBLE (-3700 2025);
FORCEADD OFFPAGE..2
(-3900 2375);
FORCEPROP 2 LAST $XR0 181 
J 0
(-3711 2375);
DISPLAY 0.638298 (-3711 2375);
PAINT MONO (-3711 2375);
FORCEPROP 2 LAST PATH I470
J 0
(-3700 2425);
DISPLAY 1.021277 (-3700 2425);
DISPLAY INVISIBLE (-3700 2425);
FORCEPROP 2 LAST CDS_LIB standard
J 0
(-3900 2375);
DISPLAY INVISIBLE (-3900 2375);
FORCEPROP 1 LAST OFFPAGE TRUE
J 0
(-3575 2250);
DISPLAY 0.872340 (-3575 2250);
PAINT GREEN (-3575 2250);
DISPLAY INVISIBLE (-3575 2250);
FORCEPROP 1 LAST COMMENT_BODY TRUE
J 0
(-3945 2280);
DISPLAY 0.872340 (-3945 2280);
PAINT GREEN (-3945 2280);
DISPLAY INVISIBLE (-3945 2280);
FORCEADD OFFPAGE..4
(-3900 2275);
FORCEPROP 2 LAST $XR0 181 
J 0
(-3714 2275);
DISPLAY 0.638298 (-3714 2275);
PAINT MONO (-3714 2275);
FORCEPROP 2 LAST PATH I471
J 0
(-3700 2325);
DISPLAY 1.021277 (-3700 2325);
DISPLAY INVISIBLE (-3700 2325);
FORCEPROP 2 LAST CDS_LIB standard
J 0
(-3900 2275);
DISPLAY INVISIBLE (-3900 2275);
FORCEPROP 1 LAST OFFPAGE TRUE
J 0
(-3575 2150);
DISPLAY 0.872340 (-3575 2150);
PAINT GREEN (-3575 2150);
DISPLAY INVISIBLE (-3575 2150);
FORCEPROP 1 LAST COMMENT_BODY TRUE
J 0
(-3925 2175);
DISPLAY 0.872340 (-3925 2175);
PAINT GREEN (-3925 2175);
DISPLAY INVISIBLE (-3925 2175);
FORCEADD OFFPAGE..2
(-3900 2675);
FORCEPROP 2 LAST $XR0 182 
J 0
(-3711 2675);
DISPLAY 0.638298 (-3711 2675);
PAINT MONO (-3711 2675);
FORCEPROP 2 LAST PATH I472
J 0
(-3700 2725);
DISPLAY 1.021277 (-3700 2725);
DISPLAY INVISIBLE (-3700 2725);
FORCEPROP 2 LAST CDS_LIB standard
J 0
(-3900 2675);
DISPLAY INVISIBLE (-3900 2675);
FORCEPROP 1 LAST OFFPAGE TRUE
J 0
(-3575 2550);
DISPLAY 0.872340 (-3575 2550);
PAINT GREEN (-3575 2550);
DISPLAY INVISIBLE (-3575 2550);
FORCEPROP 1 LAST COMMENT_BODY TRUE
J 0
(-3945 2580);
DISPLAY 0.872340 (-3945 2580);
PAINT GREEN (-3945 2580);
DISPLAY INVISIBLE (-3945 2580);
FORCEADD OFFPAGE..4
(-3900 2575);
FORCEPROP 2 LAST $XR0 182 
J 0
(-3714 2575);
DISPLAY 0.638298 (-3714 2575);
PAINT MONO (-3714 2575);
FORCEPROP 2 LAST PATH I473
J 0
(-3700 2625);
DISPLAY 1.021277 (-3700 2625);
DISPLAY INVISIBLE (-3700 2625);
FORCEPROP 2 LAST CDS_LIB standard
J 0
(-3900 2575);
DISPLAY INVISIBLE (-3900 2575);
FORCEPROP 1 LAST OFFPAGE TRUE
J 0
(-3575 2450);
DISPLAY 0.872340 (-3575 2450);
PAINT GREEN (-3575 2450);
DISPLAY INVISIBLE (-3575 2450);
FORCEPROP 1 LAST COMMENT_BODY TRUE
J 0
(-3925 2475);
DISPLAY 0.872340 (-3925 2475);
PAINT GREEN (-3925 2475);
DISPLAY INVISIBLE (-3925 2475);
FORCEADD OFFPAGE..2
(-3925 2975);
FORCEPROP 2 LAST $XR0 182 
J 0
(-3736 2975);
DISPLAY 0.638298 (-3736 2975);
PAINT MONO (-3736 2975);
FORCEPROP 2 LAST PATH I474
J 0
(-3725 3025);
DISPLAY 1.021277 (-3725 3025);
DISPLAY INVISIBLE (-3725 3025);
FORCEPROP 2 LAST CDS_LIB standard
J 0
(-3925 2975);
DISPLAY INVISIBLE (-3925 2975);
FORCEPROP 1 LAST OFFPAGE TRUE
J 0
(-3600 2850);
DISPLAY 0.872340 (-3600 2850);
PAINT GREEN (-3600 2850);
DISPLAY INVISIBLE (-3600 2850);
FORCEPROP 1 LAST COMMENT_BODY TRUE
J 0
(-3970 2880);
DISPLAY 0.872340 (-3970 2880);
PAINT GREEN (-3970 2880);
DISPLAY INVISIBLE (-3970 2880);
FORCEADD OFFPAGE..4
(-3925 2875);
FORCEPROP 2 LAST $XR0 182 
J 0
(-3739 2875);
DISPLAY 0.638298 (-3739 2875);
PAINT MONO (-3739 2875);
FORCEPROP 2 LAST PATH I475
J 0
(-3725 2925);
DISPLAY 1.021277 (-3725 2925);
DISPLAY INVISIBLE (-3725 2925);
FORCEPROP 2 LAST CDS_LIB standard
J 0
(-3925 2875);
DISPLAY INVISIBLE (-3925 2875);
FORCEPROP 1 LAST OFFPAGE TRUE
J 0
(-3600 2750);
DISPLAY 0.872340 (-3600 2750);
PAINT GREEN (-3600 2750);
DISPLAY INVISIBLE (-3600 2750);
FORCEPROP 1 LAST COMMENT_BODY TRUE
J 0
(-3950 2775);
DISPLAY 0.872340 (-3950 2775);
PAINT GREEN (-3950 2775);
DISPLAY INVISIBLE (-3950 2775);
FORCEADD OFFPAGE..2
(-3900 5375);
FORCEPROP 2 LAST $XR0 177 
J 0
(-3711 5375);
DISPLAY 0.638298 (-3711 5375);
PAINT MONO (-3711 5375);
FORCEPROP 2 LAST PATH I476
J 0
(-3575 5425);
DISPLAY 1.021277 (-3575 5425);
DISPLAY INVISIBLE (-3575 5425);
FORCEPROP 1 LAST COMMENT_BODY TRUE
J 0
(-3945 5280);
DISPLAY 0.872340 (-3945 5280);
PAINT GREEN (-3945 5280);
DISPLAY INVISIBLE (-3945 5280);
FORCEPROP 1 LAST OFFPAGE TRUE
J 0
(-3575 5250);
DISPLAY 0.872340 (-3575 5250);
PAINT GREEN (-3575 5250);
DISPLAY INVISIBLE (-3575 5250);
FORCEPROP 2 LAST CDS_LIB standard
J 0
(-3900 5375);
DISPLAY INVISIBLE (-3900 5375);
FORCEADD OFFPAGE..4
(-3900 5275);
FORCEPROP 2 LAST $XR0 177 
J 0
(-3714 5275);
DISPLAY 0.638298 (-3714 5275);
PAINT MONO (-3714 5275);
FORCEPROP 2 LAST PATH I477
J 0
(-3575 5325);
DISPLAY 1.021277 (-3575 5325);
DISPLAY INVISIBLE (-3575 5325);
FORCEPROP 1 LAST COMMENT_BODY TRUE
J 0
(-3925 5175);
DISPLAY 0.872340 (-3925 5175);
PAINT GREEN (-3925 5175);
DISPLAY INVISIBLE (-3925 5175);
FORCEPROP 1 LAST OFFPAGE TRUE
J 0
(-3575 5150);
DISPLAY 0.872340 (-3575 5150);
PAINT GREEN (-3575 5150);
DISPLAY INVISIBLE (-3575 5150);
FORCEPROP 2 LAST CDS_LIB standard
J 0
(-3900 5275);
DISPLAY INVISIBLE (-3900 5275);
FORCEADD OFFPAGE..2
(-3900 5075);
FORCEPROP 2 LAST $XR0 177 
J 0
(-3711 5075);
DISPLAY 0.638298 (-3711 5075);
PAINT MONO (-3711 5075);
FORCEPROP 2 LAST PATH I478
J 0
(-3700 5125);
DISPLAY 1.021277 (-3700 5125);
DISPLAY INVISIBLE (-3700 5125);
FORCEPROP 1 LAST COMMENT_BODY TRUE
J 0
(-3945 4980);
DISPLAY 0.872340 (-3945 4980);
PAINT GREEN (-3945 4980);
DISPLAY INVISIBLE (-3945 4980);
FORCEPROP 1 LAST OFFPAGE TRUE
J 0
(-3575 4950);
DISPLAY 0.872340 (-3575 4950);
PAINT GREEN (-3575 4950);
DISPLAY INVISIBLE (-3575 4950);
FORCEPROP 2 LAST CDS_LIB standard
J 0
(-3900 5075);
DISPLAY INVISIBLE (-3900 5075);
FORCEADD OFFPAGE..4
(-3900 4975);
FORCEPROP 2 LAST $XR0 177 
J 0
(-3714 4975);
DISPLAY 0.638298 (-3714 4975);
PAINT MONO (-3714 4975);
FORCEPROP 2 LAST PATH I479
J 0
(-3700 5025);
DISPLAY 1.021277 (-3700 5025);
DISPLAY INVISIBLE (-3700 5025);
FORCEPROP 1 LAST COMMENT_BODY TRUE
J 0
(-3925 4875);
DISPLAY 0.872340 (-3925 4875);
PAINT GREEN (-3925 4875);
DISPLAY INVISIBLE (-3925 4875);
FORCEPROP 1 LAST OFFPAGE TRUE
J 0
(-3575 4850);
DISPLAY 0.872340 (-3575 4850);
PAINT GREEN (-3575 4850);
DISPLAY INVISIBLE (-3575 4850);
FORCEPROP 2 LAST CDS_LIB standard
J 0
(-3900 4975);
DISPLAY INVISIBLE (-3900 4975);
FORCEADD OFFPAGE..2
(-3900 4775);
FORCEPROP 2 LAST $XR0 178 
J 0
(-3711 4775);
DISPLAY 0.638298 (-3711 4775);
PAINT MONO (-3711 4775);
FORCEPROP 2 LAST PATH I480
J 0
(-3700 4825);
DISPLAY 1.021277 (-3700 4825);
DISPLAY INVISIBLE (-3700 4825);
FORCEPROP 1 LAST COMMENT_BODY TRUE
J 0
(-3945 4680);
DISPLAY 0.872340 (-3945 4680);
PAINT GREEN (-3945 4680);
DISPLAY INVISIBLE (-3945 4680);
FORCEPROP 1 LAST OFFPAGE TRUE
J 0
(-3575 4650);
DISPLAY 0.872340 (-3575 4650);
PAINT GREEN (-3575 4650);
DISPLAY INVISIBLE (-3575 4650);
FORCEPROP 2 LAST CDS_LIB standard
J 0
(-3900 4775);
DISPLAY INVISIBLE (-3900 4775);
FORCEADD OFFPAGE..4
(-3900 4675);
FORCEPROP 2 LAST $XR0 178 
J 0
(-3714 4675);
DISPLAY 0.638298 (-3714 4675);
PAINT MONO (-3714 4675);
FORCEPROP 2 LAST PATH I481
J 0
(-3700 4725);
DISPLAY 1.021277 (-3700 4725);
DISPLAY INVISIBLE (-3700 4725);
FORCEPROP 1 LAST COMMENT_BODY TRUE
J 0
(-3925 4575);
DISPLAY 0.872340 (-3925 4575);
PAINT GREEN (-3925 4575);
DISPLAY INVISIBLE (-3925 4575);
FORCEPROP 1 LAST OFFPAGE TRUE
J 0
(-3575 4550);
DISPLAY 0.872340 (-3575 4550);
PAINT GREEN (-3575 4550);
DISPLAY INVISIBLE (-3575 4550);
FORCEPROP 2 LAST CDS_LIB standard
J 0
(-3900 4675);
DISPLAY INVISIBLE (-3900 4675);
FORCEADD OFFPAGE..2
(-3900 4475);
FORCEPROP 2 LAST $XR0 178 
J 0
(-3711 4475);
DISPLAY 0.638298 (-3711 4475);
PAINT MONO (-3711 4475);
FORCEPROP 2 LAST PATH I482
J 0
(-3700 4525);
DISPLAY 1.021277 (-3700 4525);
DISPLAY INVISIBLE (-3700 4525);
FORCEPROP 1 LAST COMMENT_BODY TRUE
J 0
(-3945 4380);
DISPLAY 0.872340 (-3945 4380);
PAINT GREEN (-3945 4380);
DISPLAY INVISIBLE (-3945 4380);
FORCEPROP 1 LAST OFFPAGE TRUE
J 0
(-3575 4350);
DISPLAY 0.872340 (-3575 4350);
PAINT GREEN (-3575 4350);
DISPLAY INVISIBLE (-3575 4350);
FORCEPROP 2 LAST CDS_LIB standard
J 0
(-3900 4475);
DISPLAY INVISIBLE (-3900 4475);
FORCEADD OFFPAGE..4
(-3900 4375);
FORCEPROP 2 LAST $XR0 178 
J 0
(-3714 4375);
DISPLAY 0.638298 (-3714 4375);
PAINT MONO (-3714 4375);
FORCEPROP 2 LAST PATH I483
J 0
(-3700 4425);
DISPLAY 1.021277 (-3700 4425);
DISPLAY INVISIBLE (-3700 4425);
FORCEPROP 1 LAST COMMENT_BODY TRUE
J 0
(-3925 4275);
DISPLAY 0.872340 (-3925 4275);
PAINT GREEN (-3925 4275);
DISPLAY INVISIBLE (-3925 4275);
FORCEPROP 1 LAST OFFPAGE TRUE
J 0
(-3575 4250);
DISPLAY 0.872340 (-3575 4250);
PAINT GREEN (-3575 4250);
DISPLAY INVISIBLE (-3575 4250);
FORCEPROP 2 LAST CDS_LIB standard
J 0
(-3900 4375);
DISPLAY INVISIBLE (-3900 4375);
FORCEADD UNIVERSAL_GND..1
(-3825 3100);
FORCEPROP 3 LASTPIN (-3825 3150) SIG_NAME GND\g
J 0
(-3815 3160);
DISPLAY 0.659574 (-3815 3160);
PAINT MONO (-3815 3160);
DISPLAY INVISIBLE (-3815 3160);
FORCEPROP 2 LAST CDS_LIB pure_quanta_power
J 0
(-3825 3100);
DISPLAY INVISIBLE (-3825 3100);
FORCEPROP 1 LAST PATH I484
J 0
(-3750 3100);
DISPLAY 0.872340 (-3750 3100);
PAINT AQUA (-3750 3100);
DISPLAY INVISIBLE (-3750 3100);
FORCEPROP 1 LAST HDL_POWER GND
J 1
(-3800 3025);
DISPLAY 0.872340 (-3800 3025);
PAINT GREEN (-3800 3025);
DISPLAY INVISIBLE (-3800 3025);
FORCEADD Q_RES..1
(-4275 3175);
FORCEPROP 1 LAST LOCATION PR32
J 0
(-4325 3225);
DISPLAY 0.489362 (-4325 3225);
PAINT SKYBLUE (-4325 3225);
FORCEPROP 0 LAST $SEC 1
J 0
(-4325 3275);
DISPLAY 0.680851 (-4325 3275);
PAINT MONO (-4325 3275);
DISPLAY INVISIBLE (-4325 3275);
FORCEPROP 0 LAST CDS_SEC 1
J 0
(-4325 3275);
DISPLAY 1.021277 (-4325 3275);
DISPLAY INVISIBLE (-4325 3275);
FORCEPROP 1 LASTPIN (-4375 3175) $PN 1
J 0
(-4363 3187);
DISPLAY 0.489362 (-4363 3187);
PAINT MONO (-4363 3187);
FORCEPROP 1 LASTPIN (-4175 3175) $PN 2
J 0
(-4213 3187);
DISPLAY 0.489362 (-4213 3187);
PAINT MONO (-4213 3187);
FORCEPROP 1 LAST PART_NUMBER CS00002JB38
J 0
(-4950 3125);
DISPLAY 0.489362 (-4950 3125);
PAINT SKYBLUE (-4950 3125);
FORCEPROP 1 LAST PACK_TYPE 0402LF
J 0
(-4175 3125);
DISPLAY 0.489362 (-4175 3125);
PAINT SKYBLUE (-4175 3125);
FORCEPROP 1 LAST WATTAGE 1/16W
J 2
(-4350 3125);
DISPLAY 0.489362 (-4350 3125);
PAINT SKYBLUE (-4350 3125);
FORCEPROP 1 LAST MATERIAL CHIP
J 0
(-4600 3125);
DISPLAY 0.489362 (-4600 3125);
PAINT SKYBLUE (-4600 3125);
FORCEPROP 1 LAST TOLERANCE 5%
J 0
(-4250 3125);
DISPLAY 0.489362 (-4250 3125);
PAINT SKYBLUE (-4250 3125);
FORCEPROP 1 LAST VALUE 0
J 2
(-4275 3125);
DISPLAY 0.489362 (-4275 3125);
PAINT SKYBLUE (-4275 3125);
FORCEPROP 2 LAST CDS_LIB pure_quanta
J 0
(-4275 3175);
DISPLAY INVISIBLE (-4275 3175);
FORCEPROP 1 LAST PATH I485
J 0
(-4325 3325);
DISPLAY 0.978723 (-4325 3325);
PAINT WHITE (-4325 3325);
DISPLAY INVISIBLE (-4325 3325);
FORCEADD OFFPAGE..2
(-3900 4175);
FORCEPROP 2 LAST $XR0 179 
J 0
(-3711 4175);
DISPLAY 0.638298 (-3711 4175);
PAINT MONO (-3711 4175);
FORCEPROP 2 LAST PATH I486
J 0
(-3700 4225);
DISPLAY 1.021277 (-3700 4225);
DISPLAY INVISIBLE (-3700 4225);
FORCEPROP 1 LAST COMMENT_BODY TRUE
J 0
(-3945 4080);
DISPLAY 0.872340 (-3945 4080);
PAINT GREEN (-3945 4080);
DISPLAY INVISIBLE (-3945 4080);
FORCEPROP 1 LAST OFFPAGE TRUE
J 0
(-3575 4050);
DISPLAY 0.872340 (-3575 4050);
PAINT GREEN (-3575 4050);
DISPLAY INVISIBLE (-3575 4050);
FORCEPROP 2 LAST CDS_LIB standard
J 0
(-3900 4175);
DISPLAY INVISIBLE (-3900 4175);
FORCEADD OFFPAGE..4
(-3900 4075);
FORCEPROP 2 LAST $XR0 179 
J 0
(-3714 4075);
DISPLAY 0.638298 (-3714 4075);
PAINT MONO (-3714 4075);
FORCEPROP 2 LAST PATH I487
J 0
(-3700 4125);
DISPLAY 1.021277 (-3700 4125);
DISPLAY INVISIBLE (-3700 4125);
FORCEPROP 1 LAST COMMENT_BODY TRUE
J 0
(-3925 3975);
DISPLAY 0.872340 (-3925 3975);
PAINT GREEN (-3925 3975);
DISPLAY INVISIBLE (-3925 3975);
FORCEPROP 1 LAST OFFPAGE TRUE
J 0
(-3575 3950);
DISPLAY 0.872340 (-3575 3950);
PAINT GREEN (-3575 3950);
DISPLAY INVISIBLE (-3575 3950);
FORCEPROP 2 LAST CDS_LIB standard
J 0
(-3900 4075);
DISPLAY INVISIBLE (-3900 4075);
FORCEADD OFFPAGE..2
(-3900 3875);
FORCEPROP 2 LAST $XR0 179 
J 0
(-3711 3875);
DISPLAY 0.638298 (-3711 3875);
PAINT MONO (-3711 3875);
FORCEPROP 2 LAST PATH I488
J 0
(-3700 3925);
DISPLAY 1.021277 (-3700 3925);
DISPLAY INVISIBLE (-3700 3925);
FORCEPROP 1 LAST COMMENT_BODY TRUE
J 0
(-3945 3780);
DISPLAY 0.872340 (-3945 3780);
PAINT GREEN (-3945 3780);
DISPLAY INVISIBLE (-3945 3780);
FORCEPROP 1 LAST OFFPAGE TRUE
J 0
(-3575 3750);
DISPLAY 0.872340 (-3575 3750);
PAINT GREEN (-3575 3750);
DISPLAY INVISIBLE (-3575 3750);
FORCEPROP 2 LAST CDS_LIB standard
J 0
(-3900 3875);
DISPLAY INVISIBLE (-3900 3875);
FORCEADD OFFPAGE..4
(-3925 3775);
FORCEPROP 2 LAST $XR0 179 
J 0
(-3739 3775);
DISPLAY 0.638298 (-3739 3775);
PAINT MONO (-3739 3775);
FORCEPROP 2 LAST PATH I489
J 0
(-3725 3825);
DISPLAY 1.021277 (-3725 3825);
DISPLAY INVISIBLE (-3725 3825);
FORCEPROP 1 LAST COMMENT_BODY TRUE
J 0
(-3950 3675);
DISPLAY 0.872340 (-3950 3675);
PAINT GREEN (-3950 3675);
DISPLAY INVISIBLE (-3950 3675);
FORCEPROP 1 LAST OFFPAGE TRUE
J 0
(-3600 3650);
DISPLAY 0.872340 (-3600 3650);
PAINT GREEN (-3600 3650);
DISPLAY INVISIBLE (-3600 3650);
FORCEPROP 2 LAST CDS_LIB standard
J 0
(-3925 3775);
DISPLAY INVISIBLE (-3925 3775);
FORCEADD UNIVERSAL_GND..1
(-3825 3400);
FORCEPROP 3 LASTPIN (-3825 3450) SIG_NAME GND\g
J 0
(-3815 3460);
DISPLAY 0.659574 (-3815 3460);
PAINT MONO (-3815 3460);
DISPLAY INVISIBLE (-3815 3460);
FORCEPROP 2 LAST CDS_LIB pure_quanta_power
J 0
(-3825 3400);
DISPLAY INVISIBLE (-3825 3400);
FORCEPROP 1 LAST PATH I490
J 0
(-3750 3400);
DISPLAY 0.872340 (-3750 3400);
PAINT AQUA (-3750 3400);
DISPLAY INVISIBLE (-3750 3400);
FORCEPROP 1 LAST HDL_POWER GND
J 1
(-3800 3325);
DISPLAY 0.872340 (-3800 3325);
PAINT GREEN (-3800 3325);
DISPLAY INVISIBLE (-3800 3325);
FORCEADD Q_RES..1
(-4275 3475);
FORCEPROP 1 LAST LOCATION PR532
J 0
(-4325 3525);
DISPLAY 0.489362 (-4325 3525);
PAINT SKYBLUE (-4325 3525);
FORCEPROP 0 LAST $SEC 1
J 0
(-4325 3550);
DISPLAY 0.680851 (-4325 3550);
PAINT MONO (-4325 3550);
DISPLAY INVISIBLE (-4325 3550);
FORCEPROP 0 LAST CDS_SEC 1
J 0
(-4325 3550);
DISPLAY 0.680851 (-4325 3550);
DISPLAY INVISIBLE (-4325 3550);
FORCEPROP 1 LASTPIN (-4375 3475) $PN 1
J 0
(-4363 3487);
DISPLAY 0.787234 (-4363 3487);
PAINT MONO (-4363 3487);
DISPLAY INVISIBLE (-4363 3487);
FORCEPROP 1 LASTPIN (-4175 3475) $PN 2
J 0
(-4213 3487);
DISPLAY 0.787234 (-4213 3487);
PAINT MONO (-4213 3487);
DISPLAY INVISIBLE (-4213 3487);
FORCEPROP 1 LAST WATTAGE 1/16W
J 2
(-4350 3425);
DISPLAY 0.489362 (-4350 3425);
PAINT SKYBLUE (-4350 3425);
FORCEPROP 1 LAST TOLERANCE 5%
J 0
(-4250 3425);
DISPLAY 0.489362 (-4250 3425);
PAINT SKYBLUE (-4250 3425);
FORCEPROP 1 LAST VALUE 0
J 2
(-4275 3425);
DISPLAY 0.489362 (-4275 3425);
PAINT SKYBLUE (-4275 3425);
FORCEPROP 1 LAST PART_NUMBER CS00002JB38
J 0
(-4950 3425);
DISPLAY 0.489362 (-4950 3425);
PAINT SKYBLUE (-4950 3425);
FORCEPROP 1 LAST PACK_TYPE 0402LF
J 0
(-4175 3425);
DISPLAY 0.489362 (-4175 3425);
PAINT SKYBLUE (-4175 3425);
FORCEPROP 1 LAST MATERIAL CHIP
J 0
(-4600 3425);
DISPLAY 0.489362 (-4600 3425);
PAINT SKYBLUE (-4600 3425);
FORCEPROP 2 LAST CDS_LIB pure_quanta
J 0
(-4275 3475);
DISPLAY INVISIBLE (-4275 3475);
FORCEPROP 1 LAST PATH I491
J 0
(-4325 3625);
DISPLAY 0.978723 (-4325 3625);
PAINT WHITE (-4325 3625);
DISPLAY INVISIBLE (-4325 3625);
FORCEADD Q_RES..2
(-7000 650);
FORCEPROP 1 LAST LOCATION PR600
J 0
(-6950 775);
DISPLAY 0.489362 (-6950 775);
PAINT SKYBLUE (-6950 775);
FORCEPROP 0 LAST $SEC 1
J 0
(-6950 800);
DISPLAY 0.680851 (-6950 800);
PAINT MONO (-6950 800);
DISPLAY INVISIBLE (-6950 800);
FORCEPROP 0 LAST CDS_SEC 1
J 0
(-6950 800);
DISPLAY 0.680851 (-6950 800);
DISPLAY INVISIBLE (-6950 800);
FORCEPROP 1 LASTPIN (-7000 750) $PN 1
J 0
(-6995 712);
DISPLAY 0.787234 (-6995 712);
PAINT MONO (-6995 712);
DISPLAY INVISIBLE (-6995 712);
FORCEPROP 1 LASTPIN (-7000 550) $PN 2
J 0
(-6995 560);
DISPLAY 0.787234 (-6995 560);
PAINT MONO (-6995 560);
DISPLAY INVISIBLE (-6995 560);
FORCEPROP 1 LAST PART_NUMBER CS24992FB07
J 0
(-6950 525);
DISPLAY 0.489362 (-6950 525);
PAINT SKYBLUE (-6950 525);
FORCEPROP 1 LAST WATTAGE 1/16W
J 0
(-6950 625);
DISPLAY 0.489362 (-6950 625);
PAINT SKYBLUE (-6950 625);
FORCEPROP 1 LAST MATERIAL EMPTY
J 0
(-6950 575);
DISPLAY 0.489362 (-6950 575);
PAINT RED (-6950 575);
FORCEPROP 1 LAST TOLERANCE 1%
J 0
(-6950 675);
DISPLAY 0.489362 (-6950 675);
PAINT SKYBLUE (-6950 675);
FORCEPROP 1 LAST VALUE 4.99K
J 0
(-6950 725);
DISPLAY 0.489362 (-6950 725);
PAINT SKYBLUE (-6950 725);
FORCEPROP 1 LAST PACK_TYPE 0402LF
J 0
(-6950 475);
DISPLAY 0.489362 (-6950 475);
PAINT SKYBLUE (-6950 475);
FORCEPROP 2 LAST CDS_LIB pure_quanta
J 0
(-7000 650);
DISPLAY INVISIBLE (-7000 650);
FORCEPROP 1 LAST PATH I492
J 0
(-6950 825);
DISPLAY 0.978723 (-6950 825);
PAINT WHITE (-6950 825);
DISPLAY INVISIBLE (-6950 825);
FORCEADD UNIVERSAL_GND..1
(-7000 450);
FORCEPROP 3 LASTPIN (-7000 500) SIG_NAME GND\g
J 0
(-6990 510);
DISPLAY 0.659574 (-6990 510);
PAINT MONO (-6990 510);
DISPLAY INVISIBLE (-6990 510);
FORCEPROP 2 LAST CDS_LIB pure_quanta_power
J 0
(-7000 450);
DISPLAY INVISIBLE (-7000 450);
FORCEPROP 1 LAST PATH I493
J 0
(-6925 450);
DISPLAY 0.872340 (-6925 450);
PAINT AQUA (-6925 450);
DISPLAY INVISIBLE (-6925 450);
FORCEPROP 1 LAST HDL_POWER GND
J 1
(-6975 375);
DISPLAY 0.872340 (-6975 375);
PAINT GREEN (-6975 375);
DISPLAY INVISIBLE (-6975 375);
FORCEADD DNS..1
(-10050 5275);
PAINT RED (-10050 5275);
FORCEPROP 2 LAST CDS_LIB mstr_misc
J 0
(-10050 5275);
DISPLAY INVISIBLE (-10050 5275);
FORCEPROP 1 LAST COMMENT_BODY TRUE
R 1
J 0
(-9975 5050);
DISPLAY 0.872340 (-9975 5050);
PAINT GREEN (-9975 5050);
DISPLAY INVISIBLE (-9975 5050);
FORCEADD DNS..1
(-7175 1300);
PAINT RED (-7175 1300);
FORCEPROP 2 LAST CDS_LIB mstr_misc
J 0
(-7175 1300);
DISPLAY INVISIBLE (-7175 1300);
FORCEPROP 1 LAST COMMENT_BODY TRUE
R 1
J 0
(-7100 1075);
DISPLAY 0.872340 (-7100 1075);
PAINT GREEN (-7100 1075);
DISPLAY INVISIBLE (-7100 1075);
FORCEADD DNS..1
(-9775 6225);
PAINT RED (-9775 6225);
FORCEPROP 2 LAST CDS_LIB mstr_misc
J 0
(-9775 6225);
DISPLAY INVISIBLE (-9775 6225);
FORCEPROP 1 LAST COMMENT_BODY TRUE
R 1
J 0
(-9700 6000);
DISPLAY 0.872340 (-9700 6000);
PAINT GREEN (-9700 6000);
DISPLAY INVISIBLE (-9700 6000);
FORCEADD DNS..1
(-9650 5250);
PAINT RED (-9650 5250);
FORCEPROP 2 LAST CDS_LIB mstr_misc
J 0
(-9650 5250);
DISPLAY INVISIBLE (-9650 5250);
FORCEPROP 1 LAST COMMENT_BODY TRUE
R 1
J 0
(-9575 5025);
DISPLAY 0.872340 (-9575 5025);
PAINT GREEN (-9575 5025);
DISPLAY INVISIBLE (-9575 5025);
FORCEADD QUANTA_TITLE_BLOCK_C..1
(-1225 150);
FORCEPROP 0 LAST CDS_CON_LAST_MODIFIED Fri Mar 11 14:53:27 2022
J 0
(-3110 165);
DISPLAY INVISIBLE (-3110 165);
FORCEPROP 1 LAST CUSTOM_TXT_CDS <CON_LAST_MODIFIED>
J 0
(-3110 165);
DISPLAY 0.978723 (-3110 165);
FORCEPROP 2 LAST CUSTOM_TXT_CDS <XR_PAGE_TITLE>
J 0
(-9115 5400);
DISPLAY 0.638298 (-9115 5400);
PAINT PINK (-9115 5400);
DISPLAY INVISIBLE (-9115 5400);
FORCEPROP 1 LAST CUSTOM_TXT_CDS <NAME_2>
J 0
(-4400 200);
FORCEPROP 1 LAST CUSTOM_TXT_CDS <NAME_1>
J 0
(-4400 325);
FORCEPROP 1 LAST CUSTOM_TXT_CDS <Q_NUMBER>
J 0
(-2628 253);
DISPLAY 1.212766 (-2628 253);
FORCEPROP 1 LAST CUSTOM_TXT_CDS <Q_PROJ>
J 0
(-3607 252);
DISPLAY 1.212766 (-3607 252);
FORCEPROP 1 LAST CUSTOM_TXT_CDS <Q_REV>
J 0
(-1409 253);
DISPLAY 1.212766 (-1409 253);
FORCEPROP 1 LAST CUSTOM_TXT_CDS <CON_PAGE_NUM> OF <CON_TOTAL_PAGES>
J 0
(-1671 168);
DISPLAY 0.978723 (-1671 168);
FORCEPROP 1 LAST Q_TITLE PVDDCR_CPU1_P0/PVDDIO_P0 VR CONTROLLER
J 0
(-10575 200);
DISPLAY 2.446809 (-10575 200);
PAINT GREEN (-10575 200);
FORCEPROP 1 LAST Q_DEPT BU9
J 1
(-4988 199);
DISPLAY 1.957447 (-4988 199);
PAINT GREEN (-4988 199);
FORCEPROP 1 LAST CDS_LMAN_SYM_OUTLINE -9475,6775,100,-125
J 0
(-1225 150);
DISPLAY 0.468085 (-1225 150);
PAINT GREEN (-1225 150);
DISPLAY INVISIBLE (-1225 150);
FORCEPROP 2 LAST CDS_LIB pure_quanta
J 0
(-1225 150);
DISPLAY INVISIBLE (-1225 150);
FORCEPROP 2 LAST PAGE_BORDER TRUE
J 0
(-9115 5400);
DISPLAY 0.638298 (-9115 5400);
PAINT PINK (-9115 5400);
DISPLAY INVISIBLE (-9115 5400);
FORCEPROP 1 LAST COMMENT_BODY TRUE
J 0
(-1213 137);
DISPLAY 0.978723 (-1213 137);
PAINT GREEN (-1213 137);
DISPLAY INVISIBLE (-1213 137);
FORCEPROP 2 LAST CDS_XR_PAGE_TITLE CR-176 : @T6G_MB_LIB.T6G(SCH_1):PAGE176
J 0
(-9115 5400);
DISPLAY 0.638298 (-9115 5400);
PAINT PINK (-9115 5400);
DISPLAY INVISIBLE (-9115 5400);
FORCEADD DNS..1
(-6975 650);
PAINT RED (-6975 650);
FORCEPROP 2 LAST CDS_LIB mstr_misc
J 0
(-6975 650);
DISPLAY INVISIBLE (-6975 650);
FORCEPROP 1 LAST COMMENT_BODY TRUE
R 1
J 0
(-6900 425);
DISPLAY 0.872340 (-6900 425);
PAINT GREEN (-6900 425);
DISPLAY INVISIBLE (-6900 425);
FORCEADD DNS..1
(-10150 6275);
PAINT RED (-10150 6275);
FORCEPROP 2 LAST CDS_LIB mstr_misc
J 0
(-10150 6275);
DISPLAY INVISIBLE (-10150 6275);
FORCEPROP 1 LAST COMMENT_BODY TRUE
R 1
J 0
(-10075 6050);
DISPLAY 0.872340 (-10075 6050);
PAINT GREEN (-10075 6050);
DISPLAY INVISIBLE (-10075 6050);
FORCEADD DNS..1
(-7225 6550);
PAINT RED (-7225 6550);
FORCEPROP 2 LAST CDS_LIB mstr_misc
J 0
(-7225 6550);
DISPLAY INVISIBLE (-7225 6550);
FORCEPROP 1 LAST COMMENT_BODY TRUE
R 1
J 0
(-7150 6325);
DISPLAY 0.872340 (-7150 6325);
PAINT GREEN (-7150 6325);
DISPLAY INVISIBLE (-7150 6325);
FORCEADD DNS..1
(-9425 5250);
PAINT RED (-9425 5250);
FORCEPROP 2 LAST CDS_LIB mstr_misc
J 0
(-9425 5250);
DISPLAY INVISIBLE (-9425 5250);
FORCEPROP 1 LAST COMMENT_BODY TRUE
R 1
J 0
(-9350 5025);
DISPLAY 0.872340 (-9350 5025);
PAINT GREEN (-9350 5025);
DISPLAY INVISIBLE (-9350 5025);
FORCEADD DNS..1
(-9850 5300);
PAINT RED (-9850 5300);
FORCEPROP 2 LAST CDS_LIB mstr_misc
J 0
(-9850 5300);
DISPLAY INVISIBLE (-9850 5300);
FORCEPROP 1 LAST COMMENT_BODY TRUE
R 1
J 0
(-9775 5075);
DISPLAY 0.872340 (-9775 5075);
PAINT GREEN (-9775 5075);
DISPLAY INVISIBLE (-9775 5075);
FORCEADD DNS..1
(-9575 6225);
PAINT RED (-9575 6225);
FORCEPROP 2 LAST CDS_LIB mstr_misc
J 0
(-9575 6225);
DISPLAY INVISIBLE (-9575 6225);
FORCEPROP 1 LAST COMMENT_BODY TRUE
R 1
J 0
(-9500 6000);
DISPLAY 0.872340 (-9500 6000);
PAINT GREEN (-9500 6000);
DISPLAY INVISIBLE (-9500 6000);
FORCEADD DNS..1
(-9350 6225);
PAINT RED (-9350 6225);
FORCEPROP 2 LAST CDS_LIB mstr_misc
J 0
(-9350 6225);
DISPLAY INVISIBLE (-9350 6225);
FORCEPROP 1 LAST COMMENT_BODY TRUE
R 1
J 0
(-9275 6000);
DISPLAY 0.872340 (-9275 6000);
PAINT GREEN (-9275 6000);
DISPLAY INVISIBLE (-9275 6000);
WIRE 16 -1 (-8450 1275)(-8075 1275);
WIRE 16 -1 (-8450 1275)(-8450 1325);
WIRE 16 -1 (-8225 2750)(-8225 2700);
WIRE 16 -1 (-8225 2750)(-8650 2750);
WIRE 16 -1 (-8225 3850)(-8225 3800);
WIRE 16 -1 (-8225 3850)(-8650 3850);
WIRE 16 -1 (-8500 6525)(-8175 6525);
WIRE 16 -1 (-8500 6525)(-8500 6575);
WIRE 16 -1 (-6675 500)(-6675 550);
WIRE 16 -1 (-7075 1275)(-6525 1275);
WIRE 16 -1 (-4350 800)(-4350 900);
WIRE 16 -1 (-7150 6100)(-6575 6100);
WIRE 16 -1 (-7125 6525)(-6575 6525);
WIRE 16 -1 (-6925 2000)(-6675 2000);
WIRE 16 -1 (-9700 1450)(-9700 1350);
WIRE 16 -1 (-8675 1025)(-8925 1025);
WIRE 16 -1 (-4350 1375)(-4350 1475);
WIRE 16 -1 (-4350 6100)(-4350 6050);
WIRE 16 -1 (-4350 5575)(-4350 5625);
WIRE 16 -1 (-4675 5650)(-4675 5575);
WIRE 16 -1 (-4675 6125)(-4675 6050);
WIRE 16 -1 (-3825 3175)(-3825 3150);
WIRE 16 -1 (-4175 3175)(-3825 3175);
WIRE 16 -1 (-3825 3475)(-3825 3450);
WIRE 16 -1 (-4175 3475)(-3825 3475);
WIRE 16 -1 (-7000 550)(-7000 500);
WIRE 16 -1 (-7250 4925)(-6400 4925);
FORCEPROP 2 LAST SIG_NAME PVDDCR_CPU1_P0_SMB_ALERT_R
J 0
(-7085 4935);
DISPLAY 0.489362 (-7085 4935);
FORCEPROP 2 LASTPROP $XRERR UNIQUE?
J 0
(-7325 4935);
DISPLAY 0.638298 (-7325 4935);
PAINT MONO (-7325 4935);
DISPLAY INVISIBLE (-7325 4935);
WIRE 16 -1 (-8025 4625)(-8025 4525);
WIRE 16 -1 (-8025 4525)(-8600 4525);
WIRE 16 -1 (-8350 5225)(-7450 5225);
FORCEPROP 2 LAST SIG_NAME SMB_SCM_6_R1_SCL
J 0
(-8135 5235);
DISPLAY 0.489362 (-8135 5235);
WIRE 16 -1 (-7250 5225)(-6400 5225);
FORCEPROP 2 LAST SIG_NAME SMB_CLK_PVDDCR_CPU1_P0_R
J 0
(-7085 5235);
DISPLAY 0.489362 (-7085 5235);
FORCEPROP 2 LASTPROP $XRERR UNIQUE?
J 0
(-7325 5235);
DISPLAY 0.638298 (-7325 5235);
PAINT MONO (-7325 5235);
DISPLAY INVISIBLE (-7325 5235);
WIRE 16 -1 (-8350 5075)(-7450 5075);
FORCEPROP 2 LAST SIG_NAME SMB_SCM_6_R1_SDA
J 0
(-8135 5085);
DISPLAY 0.489362 (-8135 5085);
WIRE 16 -1 (-7250 850)(-7000 850);
WIRE 16 -1 (-7000 850)(-6675 850);
WIRE 16 -1 (-7000 750)(-7000 850);
WIRE 16 -1 (-6675 850)(-6675 925);
FORCEPROP 2 LAST SIG_NAME PVDDCR_CPU1_P0_VINSEN
J 0
(-6960 950);
DISPLAY 0.489362 (-6960 950);
FORCEPROP 2 LASTPROP $XRERR UNIQUE?
J 0
(-7200 950);
DISPLAY 0.638298 (-7200 950);
PAINT MONO (-7200 950);
DISPLAY INVISIBLE (-7200 950);
WIRE 16 -1 (-6675 750)(-6675 850);
WIRE 16 -1 (-6400 925)(-6675 925);
WIRE 16 -1 (-6450 750)(-6450 825);
WIRE 16 -1 (-6450 825)(-6400 825);
WIRE 16 -1 (-7800 975)(-7800 1025);
WIRE 16 -1 (-6400 1025)(-7800 1025);
FORCEPROP 2 LAST SIG_NAME PVDDCR_CPU1_P0_VMON
J 0
(-6925 1035);
DISPLAY 0.489362 (-6925 1035);
FORCEPROP 2 LASTPROP $XRERR UNIQUE?
J 0
(-7165 1035);
DISPLAY 0.638298 (-7165 1035);
PAINT MONO (-7165 1035);
DISPLAY INVISIBLE (-7165 1035);
WIRE 16 -1 (-7800 1025)(-8250 1025);
WIRE 16 -1 (-8475 1025)(-8250 1025);
WIRE 16 -1 (-8250 950)(-8250 1025);
WIRE 16 -1 (-7875 1125)(-7500 1125);
WIRE 16 -1 (-7500 1125)(-6400 1125);
FORCEPROP 2 LAST SIG_NAME PWRGD_PVDDIO_P0_R
J 0
(-6925 1135);
DISPLAY 0.489362 (-6925 1135);
FORCEPROP 2 LASTPROP $XRERR UNIQUE?
J 0
(-7165 1135);
DISPLAY 0.638298 (-7165 1135);
PAINT MONO (-7165 1135);
DISPLAY INVISIBLE (-7165 1135);
WIRE 16 -1 (-7500 1275)(-7500 1125);
WIRE 16 -1 (-7275 1275)(-7500 1275);
WIRE 16 -1 (-7500 1275)(-7875 1275);
WIRE 16 -1 (-8300 1125)(-8300 1175);
WIRE 16 -1 (-8075 1125)(-8300 1125);
WIRE 16 -1 (-8300 1175)(-9075 1175);
FORCEPROP 2 LAST SIG_NAME PWRGD_PVDDIO_P0
J 0
(-9060 1185);
DISPLAY 0.489362 (-9060 1185);
WIRE 16 -1 (-7800 775)(-7800 650);
WIRE 16 -1 (-7800 650)(-7800 600);
WIRE 16 -1 (-8250 650)(-7800 650);
WIRE 16 -1 (-8250 750)(-8250 650);
WIRE 17 273 (-10450 400)(-9250 400);
WIRE 17 273 (-10450 800)(-10450 400);
WIRE 17 273 (-9250 800)(-9250 400);
WIRE 17 273 (-10450 800)(-9250 800);
WIRE 17 273 (-2900 4325)(-1300 4325);
WIRE 17 273 (-2900 5375)(-2900 4325);
WIRE 17 273 (-1300 5375)(-1300 4325);
WIRE 17 273 (-2900 5375)(-1300 5375);
WIRE 16 -1 (-9350 1725)(-9700 1725);
WIRE 16 -1 (-9700 1725)(-9700 1650);
WIRE 16 -1 (-9850 1725)(-9700 1725);
FORCEPROP 2 LAST SIG_NAME PVDDIO_P0_EN_R
J 0
(-9785 1735);
DISPLAY 0.489362 (-9785 1735);
FORCEPROP 2 LASTPROP $XRERR UNIQUE?
J 0
(-10025 1735);
DISPLAY 0.638298 (-10025 1735);
PAINT MONO (-10025 1735);
DISPLAY INVISIBLE (-10025 1735);
WIRE 16 -1 (-5050 4075)(-3950 4075);
FORCEPROP 2 LAST SIG_NAME PVDDCR_CPU1_P0_IMON5
J 0
(-4860 4085);
DISPLAY 0.489362 (-4860 4085);
WIRE 16 -1 (-10350 1725)(-10050 1725);
FORCEPROP 2 LAST SIG_NAME PVDDIO_P0_EN
J 0
(-10360 1735);
DISPLAY 0.489362 (-10360 1735);
WIRE 17 273 (-10175 2825)(-10175 3375);
WIRE 17 273 (-10175 2825)(-9850 2825);
WIRE 17 273 (-10175 3375)(-9850 3375);
WIRE 17 273 (-9850 3375)(-9850 2825);
WIRE 16 -1 (-8350 4925)(-7450 4925);
FORCEPROP 2 LAST SIG_NAME PVDDCR_CPU1_P0_SMB_ALERT
J 0
(-8335 4935);
DISPLAY 0.489362 (-8335 4935);
WIRE 16 -1 (-9600 6150)(-9600 5775);
WIRE 16 -1 (-9600 5775)(-6400 5775);
FORCEPROP 2 LAST SIG_NAME SVID_PVDDCR_CPU1_P0_SVD_R
J 0
(-7135 5785);
DISPLAY 0.489362 (-7135 5785);
WIRE 16 -1 (-9675 5775)(-9600 5775);
WIRE 16 -1 (-9675 5375)(-9675 5775);
WIRE 16 -1 (-10175 5775)(-9675 5775);
WIRE 16 -1 (-9350 6150)(-9350 5925);
WIRE 16 -1 (-9350 5925)(-6400 5925);
FORCEPROP 2 LAST SIG_NAME SVID_PVDDCR_CPU1_P0_SVC_R
J 0
(-7135 5935);
DISPLAY 0.489362 (-7135 5935);
WIRE 16 -1 (-9425 5925)(-9350 5925);
WIRE 16 -1 (-9425 5375)(-9425 5925);
WIRE 16 -1 (-10175 5925)(-9425 5925);
WIRE 16 -1 (-7975 6225)(-7550 6225);
WIRE 16 -1 (-7550 6225)(-6400 6225);
FORCEPROP 2 LAST SIG_NAME PVDDCR_CPU1_P0_EN_R
J 0
(-6985 6235);
DISPLAY 0.489362 (-6985 6235);
FORCEPROP 2 LASTPROP $XRERR UNIQUE?
J 0
(-7225 6235);
DISPLAY 0.638298 (-7225 6235);
PAINT MONO (-7225 6235);
DISPLAY INVISIBLE (-7225 6235);
WIRE 16 -1 (-7550 6225)(-7550 6100);
WIRE 16 -1 (-7350 6100)(-7550 6100);
WIRE 16 -1 (-7550 6375)(-6400 6375);
FORCEPROP 2 LAST SIG_NAME PWRGD_PVDDCR_CPU1_P0_R
J 0
(-6985 6385);
DISPLAY 0.489362 (-6985 6385);
FORCEPROP 2 LASTPROP $XRERR UNIQUE?
J 0
(-7225 6385);
DISPLAY 0.638298 (-7225 6385);
PAINT MONO (-7225 6385);
DISPLAY INVISIBLE (-7225 6385);
WIRE 16 -1 (-7550 6375)(-7550 6525);
WIRE 16 -1 (-7550 6375)(-7975 6375);
WIRE 16 -1 (-7325 6525)(-7550 6525);
WIRE 16 -1 (-7550 6525)(-7975 6525);
WIRE 16 -1 (-5050 4975)(-3950 4975);
FORCEPROP 2 LAST SIG_NAME PVDDCR_CPU1_P0_IMON2
J 0
(-4860 4985);
DISPLAY 0.489362 (-4860 4985);
WIRE 16 -1 (-6400 5475)(-7975 5475);
FORCEPROP 2 LAST SIG_NAME SVID_PVDDCR_CPU1_P0_SVTI_R
J 0
(-7135 5485);
DISPLAY 0.489362 (-7135 5485);
FORCEPROP 2 LASTPROP $XRERR UNIQUE?
J 0
(-7375 5485);
DISPLAY 0.638298 (-7375 5485);
PAINT MONO (-7375 5485);
DISPLAY INVISIBLE (-7375 5485);
WIRE 16 -1 (-5050 2975)(-3975 2975);
FORCEPROP 2 LAST SIG_NAME PVDDIO_P0_PWM4
J 0
(-4860 2985);
DISPLAY 0.489362 (-4860 2985);
WIRE 16 -1 (-4375 3175)(-5050 3175);
FORCEPROP 2 LAST SIG_NAME NC_PVDDCR_CPU1_P0_IMON8
J 0
(-4935 3175);
DISPLAY 0.489362 (-4935 3175);
FORCEPROP 2 LASTPROP $XRERR UNIQUE?
J 0
(-5175 3175);
DISPLAY 0.638298 (-5175 3175);
PAINT MONO (-5175 3175);
DISPLAY INVISIBLE (-5175 3175);
WIRE 16 -1 (-3975 2875)(-5050 2875);
FORCEPROP 2 LAST SIG_NAME PVDDIO_P0_IMON4
J 0
(-4860 2885);
DISPLAY 0.489362 (-4860 2885);
WIRE 16 -1 (-5050 3575)(-3950 3575);
FORCEPROP 2 LAST SIG_NAME NC_PVDDCR_CPU1_P0_PWM7
J 0
(-4885 3585);
DISPLAY 0.489362 (-4885 3585);
FORCEPROP 2 LASTPROP $XRERR UNIQUE?
J 0
(-3920 3575);
DISPLAY 0.638298 (-3920 3575);
PAINT MONO (-3920 3575);
DISPLAY INVISIBLE (-3920 3575);
WIRE 16 -1 (-6400 5625)(-7975 5625);
FORCEPROP 2 LAST SIG_NAME SVID_PVDDCR_CPU1_P0_SVTO_R
J 0
(-7135 5635);
DISPLAY 0.489362 (-7135 5635);
FORCEPROP 2 LASTPROP $XRERR UNIQUE?
J 0
(-7375 5635);
DISPLAY 0.638298 (-7375 5635);
PAINT MONO (-7375 5635);
DISPLAY INVISIBLE (-7375 5635);
WIRE 16 -1 (-7250 5075)(-6400 5075);
FORCEPROP 2 LAST SIG_NAME SMB_DIO_PVDDCR_CPU1_P0_R
J 0
(-7085 5085);
DISPLAY 0.489362 (-7085 5085);
FORCEPROP 2 LASTPROP $XRERR UNIQUE?
J 0
(-7325 5085);
DISPLAY 0.638298 (-7325 5085);
PAINT MONO (-7325 5085);
DISPLAY INVISIBLE (-7325 5085);
WIRE 16 -1 (-6575 3225)(-6400 3225);
WIRE 16 -1 (-6575 3275)(-6575 3225);
WIRE 16 -1 (-6575 3275)(-7225 3275);
FORCEPROP 2 LAST SIG_NAME VSENSE_PVDDIO_P0_VSEN1
J 0
(-7035 3285);
DISPLAY 0.489362 (-7035 3285);
FORCEPROP 2 LASTPROP $XRERR UNIQUE?
J 0
(-7275 3285);
DISPLAY 0.638298 (-7275 3285);
PAINT MONO (-7275 3285);
DISPLAY INVISIBLE (-7275 3285);
WIRE 16 -1 (-7225 3200)(-7225 3275);
WIRE 16 -1 (-7575 3275)(-7225 3275);
WIRE 16 -1 (-5050 2675)(-3950 2675);
FORCEPROP 0 LAST SIG_NAME PVDDIO_P0_PWM3
J 0
(-4860 2685);
DISPLAY 0.489362 (-4860 2685);
WIRE 16 -1 (-5050 5075)(-3950 5075);
FORCEPROP 2 LAST SIG_NAME PVDDCR_CPU1_P0_PWM2
J 0
(-4860 5085);
DISPLAY 0.489362 (-4860 5085);
WIRE 16 -1 (-5050 5275)(-3950 5275);
FORCEPROP 2 LAST SIG_NAME PVDDCR_CPU1_P0_IMON1
J 0
(-4860 5285);
DISPLAY 0.489362 (-4860 5285);
WIRE 16 -1 (-5050 5375)(-3950 5375);
FORCEPROP 2 LAST SIG_NAME PVDDCR_CPU1_P0_PWM1
J 0
(-4860 5385);
DISPLAY 0.489362 (-4860 5385);
WIRE 16 -1 (-5050 4675)(-3950 4675);
FORCEPROP 2 LAST SIG_NAME PVDDCR_CPU1_P0_IMON3
J 0
(-4860 4685);
DISPLAY 0.489362 (-4860 4685);
WIRE 16 -1 (-9200 1550)(-8550 1550);
WIRE 16 -1 (-9200 1625)(-9200 1550);
WIRE 16 -1 (-9200 1550)(-9200 1500);
WIRE 16 -1 (-8550 1550)(-8550 1575);
WIRE 16 -1 (-8550 2550)(-9200 2550);
WIRE 16 -1 (-8550 2450)(-8550 2550);
WIRE 16 -1 (-9200 2550)(-9200 2600);
WIRE 16 -1 (-9200 2450)(-9200 2550);
WIRE 16 -1 (-7925 2750)(-7925 2675);
WIRE 16 -1 (-7925 2675)(-7575 2675);
WIRE 16 -1 (-8000 2525)(-7425 2525);
FORCEPROP 2 LAST SIG_NAME PVDDCR_CPU1_P0_RESET_N
J 0
(-7985 2535);
DISPLAY 0.489362 (-7985 2535);
WIRE 16 -1 (-7575 2000)(-7575 2025);
WIRE 16 -1 (-7425 2000)(-7575 2000);
WIRE 16 -1 (-7425 2000)(-7425 2125);
WIRE 16 -1 (-7125 2000)(-7425 2000);
WIRE 16 -1 (-6400 2125)(-7425 2125);
WIRE 16 -1 (-7425 2250)(-7425 2125);
WIRE 16 -1 (-6875 2250)(-7425 2250);
WIRE 16 -1 (-6400 1625)(-7350 1625);
FORCEPROP 2 LAST SIG_NAME PVDDCR_CPU1_P0_EN1_ADDR_CFG
J 0
(-7135 1635);
DISPLAY 0.489362 (-7135 1635);
FORCEPROP 2 LASTPROP $XRERR UNIQUE?
J 0
(-7375 1635);
DISPLAY 0.638298 (-7375 1635);
PAINT MONO (-7375 1635);
DISPLAY INVISIBLE (-7375 1635);
WIRE 16 -1 (-7350 1800)(-7350 1625);
WIRE 16 -1 (-7350 1800)(-8550 1800);
WIRE 16 -1 (-8550 1800)(-8550 1850);
WIRE 16 -1 (-8550 1775)(-8550 1800);
WIRE 16 -1 (-7225 2525)(-7125 2525);
WIRE 16 -1 (-6400 2525)(-7125 2525);
WIRE 16 -1 (-7125 2675)(-7125 2525);
FORCEPROP 2 LAST SIG_NAME PVDDCR_CPU1_P0_RESET_N_R
J 0
(-7060 2535);
DISPLAY 0.489362 (-7060 2535);
FORCEPROP 2 LASTPROP $XRERR UNIQUE?
J 0
(-7300 2535);
DISPLAY 0.638298 (-7300 2535);
PAINT MONO (-7300 2535);
DISPLAY INVISIBLE (-7300 2535);
WIRE 16 -1 (-7375 2675)(-7125 2675);
WIRE 16 -1 (-4350 1775)(-3800 1775);
WIRE 16 -1 (-4350 1775)(-4350 1675);
WIRE 16 -1 (-4350 1775)(-4800 1775);
FORCEPROP 2 LAST SIG_NAME PVDDIO_P0_TEMP1
J 0
(-4710 1785);
DISPLAY 0.489362 (-4710 1785);
WIRE 16 -1 (-4800 1775)(-4800 1475);
WIRE 16 -1 (-4800 1475)(-5050 1475);
WIRE 16 -1 (-5050 4475)(-3950 4475);
FORCEPROP 2 LAST SIG_NAME PVDDCR_CPU1_P0_PWM4
J 0
(-4860 4485);
DISPLAY 0.489362 (-4860 4485);
WIRE 16 -1 (-8000 2375)(-7425 2375);
FORCEPROP 2 LAST SIG_NAME PVDDCR_CPU1_P0_OCP_N
J 0
(-7985 2385);
DISPLAY 0.489362 (-7985 2385);
WIRE 16 -1 (-7225 2375)(-6525 2375);
WIRE 16 -1 (-6400 2375)(-6525 2375);
FORCEPROP 2 LAST SIG_NAME PVDDCR_CPU1_P0_OCP_N_R
J 0
(-6985 2385);
DISPLAY 0.489362 (-6985 2385);
FORCEPROP 2 LASTPROP $XRERR UNIQUE?
J 0
(-7225 2385);
DISPLAY 0.638298 (-7225 2385);
PAINT MONO (-7225 2385);
DISPLAY INVISIBLE (-7225 2385);
WIRE 16 -1 (-6525 2250)(-6525 2375);
WIRE 16 -1 (-6675 2250)(-6525 2250);
WIRE 17 273 (-10150 4475)(-9800 4475);
WIRE 17 273 (-10150 3925)(-10150 4475);
WIRE 17 273 (-9800 4475)(-9800 3925);
WIRE 17 273 (-10150 3925)(-9800 3925);
WIRE 16 -1 (-9200 1925)(-9200 2150);
WIRE 16 -1 (-8850 2150)(-9200 2150);
FORCEPROP 2 LAST SIG_NAME PVDDIO_P0_EN_G
J 0
(-9185 2110);
DISPLAY 0.489362 (-9185 2110);
FORCEPROP 2 LASTPROP $XRERR UNIQUE?
J 0
(-9425 2110);
DISPLAY 0.638298 (-9425 2110);
PAINT MONO (-9425 2110);
DISPLAY INVISIBLE (-9425 2110);
WIRE 16 -1 (-9200 2250)(-9200 2150);
WIRE 16 -1 (-10250 5475)(-10150 5475);
WIRE 16 -1 (-10250 5475)(-10250 5375);
WIRE 16 -1 (-10150 5475)(-8175 5475);
FORCEPROP 2 LAST SIG_NAME SVID_PVDDCR_CPU1_P0_SVTI
J 0
(-9035 5500);
DISPLAY 0.489362 (-9035 5500);
FORCEPROP 2 LASTPROP $XRERR UNIQUE?
J 0
(-9275 5500);
DISPLAY 0.638298 (-9275 5500);
PAINT MONO (-9275 5500);
DISPLAY INVISIBLE (-9275 5500);
WIRE 16 -1 (-10150 6150)(-10150 5475);
WIRE 16 -1 (-10025 4975)(-10250 4975);
WIRE 16 -1 (-10025 5175)(-10025 4975);
WIRE 16 -1 (-10025 4975)(-9850 4975);
WIRE 16 -1 (-10250 5175)(-10250 4975);
WIRE 16 -1 (-10250 4975)(-10250 4875);
WIRE 16 -1 (-9850 5175)(-9850 4975);
WIRE 16 -1 (-9850 4975)(-9675 4975);
WIRE 16 -1 (-9675 5175)(-9675 4975);
WIRE 16 -1 (-9675 4975)(-9425 4975);
WIRE 16 -1 (-9425 4975)(-9425 5175);
WIRE 16 -1 (-10025 5375)(-10025 5625);
WIRE 16 -1 (-10025 5625)(-9850 5625);
WIRE 16 -1 (-10175 5625)(-10025 5625);
WIRE 16 -1 (-9850 5625)(-9800 5625);
WIRE 16 -1 (-9850 5375)(-9850 5625);
WIRE 16 -1 (-9800 5625)(-8175 5625);
FORCEPROP 2 LAST SIG_NAME SVID_PVDDCR_CPU1_P0_SVTO
J 0
(-9035 5635);
DISPLAY 0.489362 (-9035 5635);
WIRE 16 -1 (-9800 6150)(-9800 5625);
WIRE 16 -1 (-10150 6500)(-9800 6500);
WIRE 16 -1 (-10150 6500)(-10150 6550);
WIRE 16 -1 (-10150 6350)(-10150 6500);
WIRE 16 -1 (-9800 6500)(-9600 6500);
WIRE 16 -1 (-9800 6500)(-9800 6350);
WIRE 16 -1 (-9600 6500)(-9350 6500);
WIRE 16 -1 (-9600 6350)(-9600 6500);
WIRE 16 -1 (-9350 6500)(-9350 6350);
WIRE 16 -1 (-8825 6225)(-8175 6225);
FORCEPROP 2 LAST SIG_NAME FM_PVDDCR_CPU1_P0_EN
J 0
(-8785 6235);
DISPLAY 0.489362 (-8785 6235);
WIRE 16 -1 (-8825 6375)(-8175 6375);
FORCEPROP 2 LAST SIG_NAME PWRGD_PVDDCR_CPU1_P0
J 0
(-8785 6385);
DISPLAY 0.489362 (-8785 6385);
WIRE 16 -1 (-7525 875)(-7525 850);
WIRE 16 -1 (-7525 850)(-7450 850);
WIRE 16 -1 (-7625 4375)(-7275 4375);
WIRE 16 -1 (-6575 4375)(-7275 4375);
FORCEPROP 2 LAST SIG_NAME VSENSE_PVDDCR_CPU1_P0_VSEN0
J 0
(-7160 4385);
DISPLAY 0.489362 (-7160 4385);
FORCEPROP 2 LASTPROP $XRERR UNIQUE?
J 0
(-7400 4385);
DISPLAY 0.638298 (-7400 4385);
PAINT MONO (-7400 4385);
DISPLAY INVISIBLE (-7400 4385);
WIRE 16 -1 (-7275 4300)(-7275 4375);
WIRE 16 -1 (-6575 4375)(-6575 4325);
WIRE 16 -1 (-6575 4325)(-6400 4325);
WIRE 16 -1 (-5050 6075)(-4875 6075);
WIRE 16 -1 (-4875 6075)(-4875 5900);
WIRE 16 -1 (-4875 5900)(-4675 5900);
FORCEPROP 2 LAST SIG_NAME PVDDCR_CPU1_P0_VCCS
J 0
(-4835 5910);
DISPLAY 0.489362 (-4835 5910);
WIRE 16 -1 (-4675 5900)(-4350 5900);
WIRE 16 -1 (-4675 5900)(-4675 5850);
WIRE 16 -1 (-3725 5900)(-4350 5900);
WIRE 16 -1 (-4350 5825)(-4350 5900);
WIRE 16 -1 (-4350 6375)(-4675 6375);
WIRE 16 -1 (-4000 6375)(-4350 6375);
WIRE 16 -1 (-4350 6300)(-4350 6375);
WIRE 16 -1 (-4675 6375)(-4675 6325);
WIRE 16 -1 (-4675 6375)(-5050 6375);
FORCEPROP 2 LAST SIG_NAME PVDDCR_CPU1_P0_VCC
J 0
(-4885 6385);
DISPLAY 0.489362 (-4885 6385);
FORCEPROP 2 LASTPROP $XRERR UNIQUE?
J 0
(-5125 6385);
DISPLAY 0.638298 (-5125 6385);
PAINT MONO (-5125 6385);
DISPLAY INVISIBLE (-5125 6385);
WIRE 16 -1 (-3800 1175)(-4350 1175);
FORCEPROP 2 LAST SIG_NAME PVDDCR_CPU1_P0_TEMP0
J 0
(-4735 1185);
DISPLAY 0.489362 (-4735 1185);
WIRE 16 -1 (-4350 1175)(-4350 1100);
WIRE 16 -1 (-4350 1175)(-5050 1175);
WIRE 16 -1 (-5050 2075)(-3950 2075);
FORCEPROP 2 LAST SIG_NAME PVDDIO_P0_PWM1
J 0
(-4860 2085);
DISPLAY 0.489362 (-4860 2085);
WIRE 16 -1 (-3950 1975)(-5050 1975);
FORCEPROP 2 LAST SIG_NAME PVDDIO_P0_IMON1
J 0
(-4860 1985);
DISPLAY 0.489362 (-4860 1985);
WIRE 16 -1 (-5050 2375)(-3950 2375);
FORCEPROP 2 LAST SIG_NAME PVDDIO_P0_PWM2
J 0
(-4860 2385);
DISPLAY 0.489362 (-4860 2385);
WIRE 16 -1 (-3950 2275)(-5050 2275);
FORCEPROP 2 LAST SIG_NAME PVDDIO_P0_IMON2
J 0
(-4860 2285);
DISPLAY 0.489362 (-4860 2285);
WIRE 16 -1 (-5050 4775)(-3950 4775);
FORCEPROP 2 LAST SIG_NAME PVDDCR_CPU1_P0_PWM3
J 0
(-4860 4785);
DISPLAY 0.489362 (-4860 4785);
WIRE 16 -1 (-5050 4375)(-3950 4375);
FORCEPROP 2 LAST SIG_NAME PVDDCR_CPU1_P0_IMON4
J 0
(-4860 4385);
DISPLAY 0.489362 (-4860 4385);
WIRE 16 -1 (-5050 4175)(-3950 4175);
FORCEPROP 0 LAST SIG_NAME PVDDCR_CPU1_P0_PWM5
J 0
(-4860 4185);
DISPLAY 0.489362 (-4860 4185);
WIRE 16 -1 (-5050 3875)(-3950 3875);
FORCEPROP 0 LAST SIG_NAME PVDDCR_CPU1_P0_PWM6
J 0
(-4860 3885);
DISPLAY 0.489362 (-4860 3885);
WIRE 16 -1 (-3975 3775)(-5050 3775);
FORCEPROP 2 LAST SIG_NAME PVDDCR_CPU1_P0_IMON6
J 0
(-4860 3785);
DISPLAY 0.489362 (-4860 3785);
WIRE 16 -1 (-3375 6450)(-3375 6375);
WIRE 16 -1 (-3375 6375)(-3800 6375);
WIRE 17 273 (-2900 6725)(-1300 6725);
WIRE 17 273 (-2900 6725)(-2900 5475);
WIRE 17 273 (-1300 6725)(-1300 5475);
WIRE 17 273 (-2900 5475)(-1300 5475);
WIRE 16 -1 (-3950 2575)(-5050 2575);
FORCEPROP 2 LAST SIG_NAME PVDDIO_P0_IMON3
J 0
(-4860 2585);
DISPLAY 0.489362 (-4860 2585);
WIRE 16 -1 (-4375 3475)(-5050 3475);
FORCEPROP 2 LAST SIG_NAME NC_PVDDCR_CPU1_P0_IMON7
J 0
(-4910 3485);
DISPLAY 0.489362 (-4910 3485);
FORCEPROP 2 LASTPROP $XRERR UNIQUE?
J 0
(-5150 3485);
DISPLAY 0.638298 (-5150 3485);
PAINT MONO (-5150 3485);
DISPLAY INVISIBLE (-5150 3485);
WIRE 16 -1 (-5050 3275)(-3950 3275);
FORCEPROP 2 LAST SIG_NAME NC_PVDDCR_CPU1_P0_PWM8
J 0
(-4860 3285);
DISPLAY 0.489362 (-4860 3285);
FORCEPROP 2 LASTPROP $XRERR UNIQUE?
J 0
(-3920 3275);
DISPLAY 0.638298 (-3920 3275);
PAINT MONO (-3920 3275);
DISPLAY INVISIBLE (-3920 3275);
WIRE 16 -1 (-8200 3525)(-8200 3425);
WIRE 16 -1 (-8200 3425)(-8600 3425);
WIRE 16 -1 (-7775 3275)(-8975 3275);
WIRE 16 -1 (-8975 3275)(-8975 3425);
WIRE 16 -1 (-8975 3275)(-9900 3275);
FORCEPROP 2 LAST SIG_NAME VSENSE_PVDDIO_P0_DP
J 0
(-9510 3285);
DISPLAY 0.489362 (-9510 3285);
WIRE 16 -1 (-8975 3425)(-8800 3425);
WIRE 16 -1 (-6400 4075)(-6575 4075);
WIRE 16 -1 (-6575 4000)(-6575 4075);
WIRE 16 -1 (-6575 4000)(-7275 4000);
WIRE 16 -1 (-7275 4100)(-7275 4000);
WIRE 16 -1 (-9000 4000)(-7275 4000);
WIRE 16 -1 (-9000 3850)(-9000 4000);
WIRE 16 -1 (-9000 4000)(-9900 4000);
FORCEPROP 2 LAST SIG_NAME VSENSE_VSS_SENSE_C_P0
J 2
(-9110 4010);
DISPLAY 0.489362 (-9110 4010);
WIRE 16 -1 (-9000 3850)(-8850 3850);
WIRE 16 -1 (-9900 4375)(-9000 4375);
FORCEPROP 2 LAST SIG_NAME VSENSE_PVDDCR_CPU1_P0_DP
J 0
(-9585 4385);
DISPLAY 0.489362 (-9585 4385);
WIRE 16 -1 (-7825 4375)(-9000 4375);
WIRE 16 -1 (-9000 4525)(-9000 4375);
WIRE 16 -1 (-9000 4525)(-8800 4525);
WIRE 16 -1 (-6400 2975)(-6575 2975);
WIRE 16 -1 (-6575 2900)(-6575 2975);
WIRE 16 -1 (-6575 2900)(-7225 2900);
WIRE 16 -1 (-7225 3000)(-7225 2900);
WIRE 16 -1 (-8975 2900)(-7225 2900);
WIRE 16 -1 (-9900 2900)(-8975 2900);
FORCEPROP 2 LAST SIG_NAME VSENSE_VSS_SENSE_B_P0
J 0
(-9485 2910);
DISPLAY 0.489362 (-9485 2910);
WIRE 16 -1 (-8975 2750)(-8975 2900);
WIRE 16 -1 (-8975 2750)(-8850 2750);
DOT 1 (-6525 2375);
DOT 1 (-7425 2125);
DOT 1 (-7800 650);
DOT 1 (-6675 850);
DOT 1 (-9800 5625);
DOT 1 (-4350 6375);
DOT 1 (-4675 6375);
DOT 1 (-4350 5900);
DOT 1 (-4675 5900);
DOT 1 (-7550 6525);
DOT 1 (-7550 6225);
DOT 1 (-7550 6375);
DOT 1 (-7275 4375);
DOT 1 (-4350 1775);
DOT 1 (-4350 1175);
DOT 1 (-7275 4000);
DOT 1 (-7225 3275);
DOT 1 (-7225 2900);
DOT 1 (-7425 2000);
DOT 1 (-7500 1125);
DOT 1 (-7500 1275);
DOT 1 (-7800 1025);
DOT 1 (-9600 6500);
DOT 1 (-10150 6500);
DOT 1 (-9000 4375);
DOT 1 (-9425 5925);
DOT 1 (-9675 5775);
DOT 1 (-9850 5625);
DOT 1 (-10025 5625);
DOT 1 (-10150 5475);
DOT 1 (-9675 4975);
DOT 1 (-9850 4975);
DOT 1 (-10025 4975);
DOT 1 (-10250 4975);
DOT 1 (-9000 4000);
DOT 1 (-8975 3275);
DOT 1 (-9200 2150);
DOT 1 (-8550 1800);
DOT 1 (-9200 1550);
DOT 1 (-9800 6500);
DOT 1 (-9350 5925);
DOT 1 (-9600 5775);
DOT 1 (-8975 2900);
DOT 1 (-7125 2525);
DOT 1 (-9200 2550);
DOT 1 (-9700 1725);
DOT 1 (-8250 1025);
DOT 1 (-7000 850);
FORCENOTE
PVDDCR_CPU1_P0 SPECFICATION
(-2875 6647) 0;
DISPLAY LEFT (-2875 6647);
DISPLAY 1.170213 (-2875 6647);
PAINT WHITE (-2875 6647);
FORCENOTE
MIN AC=VID-EDC*LL-110MV
(-2875 6225) 0;
DISPLAY LEFT (-2875 6225);
DISPLAY 0.936170 (-2875 6225);
PAINT WHITE (-2875 6225);
FORCENOTE
VID=0.55-2V
(-2875 6525) 0;
DISPLAY LEFT (-2875 6525);
DISPLAY 0.936170 (-2875 6525);
PAINT WHITE (-2875 6525);
FORCENOTE
RIPPLE=+/-10MV
(-2875 6450) 0;
DISPLAY LEFT (-2875 6450);
DISPLAY 0.936170 (-2875 6450);
PAINT WHITE (-2875 6450);
FORCENOTE
DC=+/-20MV
(-2875 6375) 0;
DISPLAY LEFT (-2875 6375);
DISPLAY 0.936170 (-2875 6375);
PAINT WHITE (-2875 6375);
FORCENOTE
MAX AC=+200MV
(-2875 6300) 0;
DISPLAY LEFT (-2875 6300);
DISPLAY 0.936170 (-2875 6300);
PAINT WHITE (-2875 6300);
FORCENOTE
TDC=175A
(-2875 6150) 0;
DISPLAY LEFT (-2875 6150);
DISPLAY 0.936170 (-2875 6150);
PAINT WHITE (-2875 6150);
FORCENOTE
OCP=276A (EDC*1.2)
(-2875 6000) 0;
DISPLAY LEFT (-2875 6000);
DISPLAY 0.936170 (-2875 6000);
PAINT WHITE (-2875 6000);
FORCENOTE
EDC=230A
(-2875 6075) 0;
DISPLAY LEFT (-2875 6075);
DISPLAY 0.936170 (-2875 6075);
PAINT WHITE (-2875 6075);
FORCENOTE
0X62
(-9925 625) 0;
DISPLAY LEFT (-9925 625);
DISPLAY 0.638298 (-9925 625);
PAINT WHITE (-9925 625);
FORCENOTE
ADDRESS
(-9925 725) 0;
DISPLAY LEFT (-9925 725);
DISPLAY 0.808511 (-9925 725);
PAINT WHITE (-9925 725);
FORCENOTE
LOAD STEP=200A
(-2875 5925) 0;
DISPLAY LEFT (-2875 5925);
DISPLAY 0.936170 (-2875 5925);
PAINT WHITE (-2875 5925);
FORCENOTE
SVI3 ADDRESS=PORT1 (0X1)
(-2875 5550) 0;
DISPLAY LEFT (-2875 5550);
DISPLAY 0.936170 (-2875 5550);
PAINT WHITE (-2875 5550);
FORCENOTE
EFFICIENCY > 90% @TDC
(-2875 5625) 0;
DISPLAY LEFT (-2875 5625);
DISPLAY 0.936170 (-2875 5625);
PAINT WHITE (-2875 5625);
FORCENOTE
WORK FREQUENCY=600KHZ
(-2875 5700) 0;
DISPLAY LEFT (-2875 5700);
DISPLAY 0.936170 (-2875 5700);
PAINT WHITE (-2875 5700);
FORCENOTE
LOAD-LINE=0.4MOHM
(-2875 5775) 0;
DISPLAY LEFT (-2875 5775);
DISPLAY 0.936170 (-2875 5775);
PAINT WHITE (-2875 5775);
FORCENOTE
LOAD RELEASE=200A
(-2875 5850) 0;
DISPLAY LEFT (-2875 5850);
DISPLAY 0.936170 (-2875 5850);
PAINT WHITE (-2875 5850);
FORCENOTE
PR67=CS21072FB01
(-2900 3525) 0;
DISPLAY LEFT (-2900 3525);
DISPLAY 1.021277 (-2900 3525);
PAINT WHITE (-2900 3525);
FORCENOTE
PU12=AR0T6GPV000
(-2900 3600) 0;
DISPLAY LEFT (-2900 3600);
DISPLAY 1.021277 (-2900 3600);
PAINT WHITE (-2900 3600);
FORCENOTE
2ND SOURCE:INFENEON BOM
(-2900 3675) 0;
DISPLAY LEFT (-2900 3675);
DISPLAY 1.021277 (-2900 3675);
PAINT WHITE (-2900 3675);
FORCENOTE
MAIN SOURCE:RENESAS BOM
(-2900 3925) 0;
DISPLAY LEFT (-2900 3925);
DISPLAY 1.021277 (-2900 3925);
PAINT WHITE (-2900 3925);
FORCENOTE
PU12=AR0T6GPV005
(-2900 3850) 0;
DISPLAY LEFT (-2900 3850);
DISPLAY 1.021277 (-2900 3850);
PAINT WHITE (-2900 3850);
FORCENOTE
RENESAS
(-10375 625) 0;
DISPLAY LEFT (-10375 625);
DISPLAY 0.638298 (-10375 625);
PAINT WHITE (-10375 625);
FORCENOTE
INFINEON
(-10375 550) 0;
DISPLAY LEFT (-10375 550);
DISPLAY 0.638298 (-10375 550);
PAINT WHITE (-10375 550);
FORCENOTE
MPS
(-10375 475) 0;
DISPLAY LEFT (-10375 475);
DISPLAY 0.638298 (-10375 475);
PAINT WHITE (-10375 475);
FORCENOTE
0X4E
(-9925 550) 0;
DISPLAY LEFT (-9925 550);
DISPLAY 0.638298 (-9925 550);
PAINT WHITE (-9925 550);
FORCENOTE
0X4E
(-9925 475) 0;
DISPLAY LEFT (-9925 475);
DISPLAY 0.638298 (-9925 475);
PAINT WHITE (-9925 475);
FORCENOTE
/1.07K
(-9575 550) 0;
DISPLAY LEFT (-9575 550);
DISPLAY 0.638298 (-9575 550);
PAINT WHITE (-9575 550);
FORCENOTE
/52.3K
(-9575 475) 0;
DISPLAY LEFT (-9575 475);
DISPLAY 0.638298 (-9575 475);
PAINT WHITE (-9575 475);
FORCENOTE
TRACE WIDTH = 10MIL
(-10200 3750) 0;
DISPLAY LEFT (-10200 3750);
DISPLAY 1.021277 (-10200 3750);
PAINT WHITE (-10200 3750);
FORCENOTE
TRACE SPACING = 5MIL
(-10200 3675) 0;
DISPLAY LEFT (-10200 3675);
DISPLAY 1.021277 (-10200 3675);
PAINT WHITE (-10200 3675);
FORCENOTE
VR
(-10375 725) 0;
DISPLAY LEFT (-10375 725);
DISPLAY 0.808511 (-10375 725);
PAINT WHITE (-10375 725);
FORCENOTE
PVDDIO_P0 SPECFICATION
(-2875 5300) 0;
DISPLAY LEFT (-2875 5300);
DISPLAY 1.276596 (-2875 5300);
PAINT WHITE (-2875 5300);
FORCENOTE
VID=0.9-1.2V
(-2875 5175) 0;
DISPLAY LEFT (-2875 5175);
DISPLAY 0.936170 (-2875 5175);
PAINT WHITE (-2875 5175);
FORCENOTE
RIPPLE=+/-10MV
(-2875 5100) 0;
DISPLAY LEFT (-2875 5100);
DISPLAY 0.936170 (-2875 5100);
PAINT WHITE (-2875 5100);
FORCENOTE
DC & AC=+/-80MV
(-2875 5025) 0;
DISPLAY LEFT (-2875 5025);
DISPLAY 0.936170 (-2875 5025);
PAINT WHITE (-2875 5025);
FORCENOTE
TDC=120A
(-2875 4950) 0;
DISPLAY LEFT (-2875 4950);
DISPLAY 0.936170 (-2875 4950);
PAINT WHITE (-2875 4950);
FORCENOTE
EDC=140A
(-2875 4875) 0;
DISPLAY LEFT (-2875 4875);
DISPLAY 0.936170 (-2875 4875);
PAINT WHITE (-2875 4875);
FORCENOTE
OCP=168A (EDC*1.2)
(-2875 4800) 0;
DISPLAY LEFT (-2875 4800);
DISPLAY 0.936170 (-2875 4800);
PAINT WHITE (-2875 4800);
FORCENOTE
LOAD STEP=44A
(-2875 4725) 0;
DISPLAY LEFT (-2875 4725);
DISPLAY 0.936170 (-2875 4725);
PAINT WHITE (-2875 4725);
FORCENOTE
LOAD RELEASE=37A
(-2875 4650) 0;
DISPLAY LEFT (-2875 4650);
DISPLAY 0.936170 (-2875 4650);
PAINT WHITE (-2875 4650);
FORCENOTE
WORK FREQUENCY=600KHZ
(-2875 4575) 0;
DISPLAY LEFT (-2875 4575);
DISPLAY 0.936170 (-2875 4575);
PAINT WHITE (-2875 4575);
FORCENOTE
EFFICIENCY > 90% @TDC
(-2875 4500) 0;
DISPLAY LEFT (-2875 4500);
DISPLAY 0.936170 (-2875 4500);
PAINT WHITE (-2875 4500);
FORCENOTE
SVI3 ADDRESS=PORT1 (0X2)
(-2875 4425) 0;
DISPLAY LEFT (-2875 4425);
DISPLAY 0.936170 (-2875 4425);
PAINT WHITE (-2875 4425);
FORCENOTE
BOM NOTE
(-2900 4050) 0;
DISPLAY LEFT (-2900 4050);
DISPLAY 1.276596 (-2900 4050);
PAINT WHITE (-2900 4050);
FORCENOTE
DIFFERENTIAL PAIR
(-10350 2750) 0;
DISPLAY LEFT (-10350 2750);
DISPLAY 1.021277 (-10350 2750);
PAINT WHITE (-10350 2750);
FORCENOTE
TRACE WIDTH = 10MIL
(-10350 2675) 0;
DISPLAY LEFT (-10350 2675);
DISPLAY 1.021277 (-10350 2675);
PAINT WHITE (-10350 2675);
FORCENOTE
PMBUS ADDRESS AND CONFIG
(-10475 850) 0;
DISPLAY LEFT (-10475 850);
DISPLAY 1.170213 (-10475 850);
PAINT WHITE (-10475 850);
FORCENOTE
0/1.96K
(-9575 625) 0;
DISPLAY LEFT (-9575 625);
DISPLAY 0.638298 (-9575 625);
PAINT WHITE (-9575 625);
FORCENOTE
CONFIG/R
(-9575 725) 0;
DISPLAY LEFT (-9575 725);
DISPLAY 0.808511 (-9575 725);
PAINT WHITE (-9575 725);
FORCENOTE
TRACE SPACING = 5MIL
(-10350 2600) 0;
DISPLAY LEFT (-10350 2600);
DISPLAY 1.021277 (-10350 2600);
PAINT WHITE (-10350 2600);
FORCENOTE
DIFFERENTIAL PAIR
(-10200 3825) 0;
DISPLAY LEFT (-10200 3825);
DISPLAY 1.021277 (-10200 3825);
PAINT WHITE (-10200 3825);
FORCENOTE
PC76 = CH5103KEB01
(-2900 3450) 0;
DISPLAY LEFT (-2900 3450);
DISPLAY 1.021277 (-2900 3450);
PAINT WHITE (-2900 3450);
FORCENOTE
PC77,PC78 = CH11006JB00
(-2900 3375) 0;
DISPLAY LEFT (-2900 3375);
DISPLAY 1.021277 (-2900 3375);
PAINT WHITE (-2900 3375);
FORCENOTE
PC68,PC71 = CH12206KB14
(-2900 3300) 0;
DISPLAY LEFT (-2900 3300);
DISPLAY 1.021277 (-2900 3300);
PAINT WHITE (-2900 3300);
FORCENOTE
PR53 = CS25362FB15
(-2900 3225) 0;
DISPLAY LEFT (-2900 3225);
DISPLAY 1.021277 (-2900 3225);
PAINT WHITE (-2900 3225);
FORCENOTE
3RD SOURCE:MPS BOM
(-2900 2700) 0;
DISPLAY LEFT (-2900 2700);
DISPLAY 1.021277 (-2900 2700);
PAINT WHITE (-2900 2700);
FORCENOTE
PU12=AL002857000
(-2900 2625) 0;
DISPLAY LEFT (-2900 2625);
DISPLAY 1.021277 (-2900 2625);
PAINT WHITE (-2900 2625);
FORCENOTE
PC74=TMP_QCH21006JB10
(-2900 2100) 0;
DISPLAY LEFT (-2900 2100);
DISPLAY 1.021277 (-2900 2100);
PAINT WHITE (-2900 2100);
FORCENOTE
PC77,PC78=TMP_QCH31004KB17
(-2900 1950) 0;
DISPLAY LEFT (-2900 1950);
DISPLAY 1.021277 (-2900 1950);
PAINT WHITE (-2900 1950);
FORCENOTE
PR74=CS37502FB05
(-2900 2175) 0;
DISPLAY LEFT (-2900 2175);
DISPLAY 1.021277 (-2900 2175);
PAINT WHITE (-2900 2175);
FORCENOTE
PR54=CS00002JB38
(-2900 2250) 0;
DISPLAY LEFT (-2900 2250);
DISPLAY 1.021277 (-2900 2250);
PAINT WHITE (-2900 2250);
FORCENOTE
PR67=CS36652FB03
(-2900 2325) 0;
DISPLAY LEFT (-2900 2325);
DISPLAY 1.021277 (-2900 2325);
PAINT WHITE (-2900 2325);
FORCENOTE
PR53,PC67=EMPTY
(-2900 2400) 0;
DISPLAY LEFT (-2900 2400);
DISPLAY 1.021277 (-2900 2400);
PAINT WHITE (-2900 2400);
FORCENOTE
PC68,PC71=EMPTY
(-2900 2475) 0;
DISPLAY LEFT (-2900 2475);
DISPLAY 1.021277 (-2900 2475);
PAINT WHITE (-2900 2475);
FORCENOTE
PR532,PR32=EMPTY
(-2900 2550) 0;
DISPLAY LEFT (-2900 2550);
DISPLAY 1.021277 (-2900 2550);
PAINT WHITE (-2900 2550);
FORCENOTE
PR600=CS24992FB07
(-2900 2025) 0;
DISPLAY LEFT (-2900 2025);
DISPLAY 1.021277 (-2900 2025);
PAINT WHITE (-2900 2025);
FORCENOTE
PR532,PR32 = EMPTY
(-2900 3075) 0;
DISPLAY LEFT (-2900 3075);
DISPLAY 1.021277 (-2900 3075);
PAINT WHITE (-2900 3075);
FORCENOTE
PR54 = CS21002FB24
(-2900 3150) 0;
DISPLAY LEFT (-2900 3150);
DISPLAY 1.021277 (-2900 3150);
PAINT WHITE (-2900 3150);
FORCENOTE
PR40 = CS00002JB38
(-2900 3000) 0;
DISPLAY LEFT (-2900 3000);
DISPLAY 1.021277 (-2900 3000);
PAINT WHITE (-2900 3000);
FORCENOTE
PC67 = CH3104J1B00
(-2900 2925) 0;
DISPLAY LEFT (-2900 2925);
DISPLAY 1.021277 (-2900 2925);
PAINT WHITE (-2900 2925);
QUIT
